(kicad_sch
	(version 20250114)
	(generator "eeschema")
	(generator_version "9.0")
	(paper "A3")
	(title_block
		(title "Thunderbolt to 10GbE adapter")
		(date "2026-04-23")
		(rev "1.1.0")
		(company "Antmicro Ltd")
		(comment 1 "www.antmicro.com")
	)
	(bus_alias "LSX"
		(members "LSX_R2P" "LSX_P2R")
	)
	(bus_alias "USB"
		(members "D+" "D-")
	)
	(text "USB Power Delivery Controller"
		(exclude_from_sim no)
		(at 177.8 107.95 0)
		(effects
			(font
				(size 2.54 2.54)
				(bold yes)
			)
			(justify left bottom)
		)
	)
	(text "3V3 Buck Converter"
		(exclude_from_sim no)
		(at 147.32 38.1 0)
		(effects
			(font
				(size 2.54 2.54)
				(bold yes)
			)
			(justify left bottom)
		)
	)
	(junction
		(at 135.89 62.23)
		(diameter 0)
		(color 0 0 0 0)
	)
	(junction
		(at 176.53 149.86)
		(diameter 0)
		(color 0 0 0 0)
	)
	(junction
		(at 132.08 160.02)
		(diameter 0)
		(color 0 0 0 0)
	)
	(junction
		(at 166.37 193.04)
		(diameter 0)
		(color 0 0 0 0)
	)
	(junction
		(at 214.63 59.69)
		(diameter 0)
		(color 0 0 0 0)
	)
	(junction
		(at 237.49 199.39)
		(diameter 0)
		(color 0 0 0 0)
	)
	(junction
		(at 129.54 62.23)
		(diameter 0)
		(color 0 0 0 0)
	)
	(junction
		(at 257.81 129.54)
		(diameter 0)
		(color 0 0 0 0)
	)
	(junction
		(at 129.54 43.18)
		(diameter 0)
		(color 0 0 0 0)
	)
	(junction
		(at 138.43 43.18)
		(diameter 0)
		(color 0 0 0 0)
	)
	(junction
		(at 119.38 43.18)
		(diameter 0)
		(color 0 0 0 0)
	)
	(junction
		(at 237.49 200.66)
		(diameter 0)
		(color 0 0 0 0)
	)
	(junction
		(at 229.87 59.69)
		(diameter 0)
		(color 0 0 0 0)
	)
	(junction
		(at 147.32 43.18)
		(diameter 0)
		(color 0 0 0 0)
	)
	(junction
		(at 264.16 208.28)
		(diameter 0)
		(color 0 0 0 0)
	)
	(junction
		(at 144.78 154.94)
		(diameter 0)
		(color 0 0 0 0)
	)
	(junction
		(at 165.1 165.1)
		(diameter 0)
		(color 0 0 0 0)
	)
	(junction
		(at 288.29 59.69)
		(diameter 0)
		(color 0 0 0 0)
	)
	(junction
		(at 93.98 43.18)
		(diameter 0)
		(color 0 0 0 0)
	)
	(junction
		(at 250.19 208.28)
		(diameter 0)
		(color 0 0 0 0)
	)
	(junction
		(at 259.08 160.02)
		(diameter 0)
		(color 0 0 0 0)
	)
	(junction
		(at 237.49 198.12)
		(diameter 0)
		(color 0 0 0 0)
	)
	(junction
		(at 176.53 220.98)
		(diameter 0)
		(color 0 0 0 0)
	)
	(junction
		(at 214.63 67.31)
		(diameter 0)
		(color 0 0 0 0)
	)
	(junction
		(at 267.97 129.54)
		(diameter 0)
		(color 0 0 0 0)
	)
	(junction
		(at 115.57 43.18)
		(diameter 0)
		(color 0 0 0 0)
	)
	(junction
		(at 111.76 43.18)
		(diameter 0)
		(color 0 0 0 0)
	)
	(junction
		(at 165.1 149.86)
		(diameter 0)
		(color 0 0 0 0)
	)
	(junction
		(at 176.53 144.78)
		(diameter 0)
		(color 0 0 0 0)
	)
	(junction
		(at 205.74 59.69)
		(diameter 0)
		(color 0 0 0 0)
	)
	(junction
		(at 264.16 220.98)
		(diameter 0)
		(color 0 0 0 0)
	)
	(junction
		(at 266.7 160.02)
		(diameter 0)
		(color 0 0 0 0)
	)
	(junction
		(at 205.74 67.31)
		(diameter 0)
		(color 0 0 0 0)
	)
	(junction
		(at 138.43 140.97)
		(diameter 0)
		(color 0 0 0 0)
	)
	(junction
		(at 240.03 59.69)
		(diameter 0)
		(color 0 0 0 0)
	)
	(junction
		(at 185.42 59.69)
		(diameter 0)
		(color 0 0 0 0)
	)
	(junction
		(at 107.95 238.76)
		(diameter 0)
		(color 0 0 0 0)
	)
	(junction
		(at 237.49 167.64)
		(diameter 0)
		(color 0 0 0 0)
	)
	(junction
		(at 132.08 140.97)
		(diameter 0)
		(color 0 0 0 0)
	)
	(junction
		(at 165.1 167.64)
		(diameter 0)
		(color 0 0 0 0)
	)
	(junction
		(at 138.43 157.48)
		(diameter 0)
		(color 0 0 0 0)
	)
	(junction
		(at 144.78 140.97)
		(diameter 0)
		(color 0 0 0 0)
	)
	(junction
		(at 257.81 59.69)
		(diameter 0)
		(color 0 0 0 0)
	)
	(junction
		(at 170.18 129.54)
		(diameter 0)
		(color 0 0 0 0)
	)
	(junction
		(at 176.53 134.62)
		(diameter 0)
		(color 0 0 0 0)
	)
	(junction
		(at 276.86 157.48)
		(diameter 0)
		(color 0 0 0 0)
	)
	(junction
		(at 248.92 59.69)
		(diameter 0)
		(color 0 0 0 0)
	)
	(junction
		(at 285.75 157.48)
		(diameter 0)
		(color 0 0 0 0)
	)
	(junction
		(at 153.67 74.93)
		(diameter 0)
		(color 0 0 0 0)
	)
	(junction
		(at 266.7 59.69)
		(diameter 0)
		(color 0 0 0 0)
	)
	(junction
		(at 147.32 185.42)
		(diameter 0)
		(color 0 0 0 0)
	)
	(junction
		(at 153.67 134.62)
		(diameter 0)
		(color 0 0 0 0)
	)
	(junction
		(at 288.29 63.5)
		(diameter 0)
		(color 0 0 0 0)
	)
	(junction
		(at 165.1 170.18)
		(diameter 0)
		(color 0 0 0 0)
	)
	(junction
		(at 170.18 134.62)
		(diameter 0)
		(color 0 0 0 0)
	)
	(junction
		(at 109.22 236.22)
		(diameter 0)
		(color 0 0 0 0)
	)
	(no_connect
		(at 177.8 180.34)
	)
	(no_connect
		(at 177.8 124.46)
	)
	(no_connect
		(at 177.8 195.58)
	)
	(no_connect
		(at 236.22 121.92)
	)
	(no_connect
		(at 177.8 182.88)
	)
	(no_connect
		(at 177.8 187.96)
	)
	(no_connect
		(at 236.22 124.46)
	)
	(no_connect
		(at 177.8 213.36)
	)
	(no_connect
		(at 177.8 177.8)
	)
	(no_connect
		(at 177.8 215.9)
	)
	(no_connect
		(at 177.8 121.92)
	)
	(bus_entry
		(at 116.84 153.67)
		(size 1.27 1.27)
		(stroke
			(width 0)
			(type default)
		)
	)
	(bus_entry
		(at 140.97 241.3)
		(size 2.54 2.54)
		(stroke
			(width 0)
			(type default)
		)
	)
	(bus_entry
		(at 311.15 186.69)
		(size -1.27 1.27)
		(stroke
			(width 0)
			(type default)
		)
	)
	(bus_entry
		(at 311.15 179.07)
		(size -1.27 1.27)
		(stroke
			(width 0)
			(type default)
		)
	)
	(bus_entry
		(at 311.15 158.75)
		(size -1.27 1.27)
		(stroke
			(width 0)
			(type default)
		)
	)
	(bus_entry
		(at 140.97 207.01)
		(size 1.27 1.27)
		(stroke
			(width 0)
			(type default)
		)
	)
	(bus_entry
		(at 311.15 173.99)
		(size -1.27 1.27)
		(stroke
			(width 0)
			(type default)
		)
	)
	(bus_entry
		(at 140.97 204.47)
		(size 1.27 1.27)
		(stroke
			(width 0)
			(type default)
		)
	)
	(bus_entry
		(at 140.97 201.93)
		(size 1.27 1.27)
		(stroke
			(width 0)
			(type default)
		)
	)
	(bus_entry
		(at 140.97 243.84)
		(size 2.54 2.54)
		(stroke
			(width 0)
			(type default)
		)
	)
	(bus_entry
		(at 311.15 156.21)
		(size -1.27 1.27)
		(stroke
			(width 0)
			(type default)
		)
	)
	(bus_entry
		(at 97.79 233.68)
		(size 2.54 2.54)
		(stroke
			(width 0)
			(type default)
		)
	)
	(bus_entry
		(at 140.97 228.6)
		(size 2.54 2.54)
		(stroke
			(width 0)
			(type default)
		)
	)
	(bus_entry
		(at 97.79 236.22)
		(size 2.54 2.54)
		(stroke
			(width 0)
			(type default)
		)
	)
	(bus_entry
		(at 311.15 171.45)
		(size -1.27 1.27)
		(stroke
			(width 0)
			(type default)
		)
	)
	(bus_entry
		(at 116.84 156.21)
		(size 1.27 1.27)
		(stroke
			(width 0)
			(type default)
		)
	)
	(bus_entry
		(at 311.15 189.23)
		(size -1.27 1.27)
		(stroke
			(width 0)
			(type default)
		)
	)
	(bus_entry
		(at 311.15 181.61)
		(size -1.27 1.27)
		(stroke
			(width 0)
			(type default)
		)
	)
	(bus_entry
		(at 140.97 226.06)
		(size 2.54 2.54)
		(stroke
			(width 0)
			(type default)
		)
	)
	(bus_entry
		(at 116.84 158.75)
		(size 1.27 1.27)
		(stroke
			(width 0)
			(type default)
		)
	)
	(bus_entry
		(at 140.97 199.39)
		(size 1.27 1.27)
		(stroke
			(width 0)
			(type default)
		)
	)
	(wire
		(pts
			(xy 173.99 167.64) (xy 177.8 167.64)
		)
		(stroke
			(width 0)
			(type default)
		)
	)
	(wire
		(pts
			(xy 245.11 231.14) (xy 252.73 231.14)
		)
		(stroke
			(width 0)
			(type default)
		)
	)
	(wire
		(pts
			(xy 129.54 69.85) (xy 129.54 72.39)
		)
		(stroke
			(width 0)
			(type default)
		)
	)
	(wire
		(pts
			(xy 237.49 167.64) (xy 241.3 167.64)
		)
		(stroke
			(width 0)
			(type default)
		)
	)
	(wire
		(pts
			(xy 144.78 154.94) (xy 177.8 154.94)
		)
		(stroke
			(width 0)
			(type default)
		)
	)
	(wire
		(pts
			(xy 236.22 198.12) (xy 237.49 198.12)
		)
		(stroke
			(width 0)
			(type default)
		)
	)
	(wire
		(pts
			(xy 236.22 220.98) (xy 264.16 220.98)
		)
		(stroke
			(width 0)
			(type default)
		)
	)
	(wire
		(pts
			(xy 236.22 157.48) (xy 276.86 157.48)
		)
		(stroke
			(width 0)
			(type default)
		)
	)
	(wire
		(pts
			(xy 236.22 195.58) (xy 237.49 195.58)
		)
		(stroke
			(width 0)
			(type default)
		)
	)
	(wire
		(pts
			(xy 165.1 167.64) (xy 168.91 167.64)
		)
		(stroke
			(width 0)
			(type default)
		)
	)
	(wire
		(pts
			(xy 205.74 66.04) (xy 205.74 67.31)
		)
		(stroke
			(width 0)
			(type default)
		)
	)
	(wire
		(pts
			(xy 173.99 185.42) (xy 177.8 185.42)
		)
		(stroke
			(width 0)
			(type default)
		)
	)
	(wire
		(pts
			(xy 236.22 236.22) (xy 240.03 236.22)
		)
		(stroke
			(width 0)
			(type default)
		)
	)
	(wire
		(pts
			(xy 144.78 140.97) (xy 144.78 146.05)
		)
		(stroke
			(width 0)
			(type default)
		)
	)
	(wire
		(pts
			(xy 281.94 59.69) (xy 288.29 59.69)
		)
		(stroke
			(width 0)
			(type default)
		)
	)
	(wire
		(pts
			(xy 236.22 142.24) (xy 237.49 142.24)
		)
		(stroke
			(width 0)
			(type default)
		)
	)
	(wire
		(pts
			(xy 153.67 135.89) (xy 153.67 134.62)
		)
		(stroke
			(width 0)
			(type default)
		)
	)
	(bus
		(pts
			(xy 115.57 148.59) (xy 116.84 149.86)
		)
		(stroke
			(width 0)
			(type default)
		)
	)
	(wire
		(pts
			(xy 176.53 144.78) (xy 176.53 149.86)
		)
		(stroke
			(width 0)
			(type default)
		)
	)
	(wire
		(pts
			(xy 236.22 132.08) (xy 237.49 132.08)
		)
		(stroke
			(width 0)
			(type default)
		)
	)
	(wire
		(pts
			(xy 205.74 59.69) (xy 214.63 59.69)
		)
		(stroke
			(width 0)
			(type default)
		)
	)
	(wire
		(pts
			(xy 153.67 72.39) (xy 153.67 74.93)
		)
		(stroke
			(width 0)
			(type default)
		)
	)
	(wire
		(pts
			(xy 242.57 147.32) (xy 252.73 147.32)
		)
		(stroke
			(width 0)
			(type default)
		)
	)
	(wire
		(pts
			(xy 276.86 157.48) (xy 276.86 161.29)
		)
		(stroke
			(width 0)
			(type default)
		)
	)
	(wire
		(pts
			(xy 107.95 232.41) (xy 107.95 238.76)
		)
		(stroke
			(width 0)
			(type default)
		)
	)
	(wire
		(pts
			(xy 245.11 241.3) (xy 252.73 241.3)
		)
		(stroke
			(width 0)
			(type default)
		)
	)
	(wire
		(pts
			(xy 236.22 215.9) (xy 240.03 215.9)
		)
		(stroke
			(width 0)
			(type default)
		)
	)
	(wire
		(pts
			(xy 132.08 139.7) (xy 132.08 140.97)
		)
		(stroke
			(width 0)
			(type default)
		)
	)
	(wire
		(pts
			(xy 190.5 72.39) (xy 180.34 72.39)
		)
		(stroke
			(width 0)
			(type default)
		)
	)
	(wire
		(pts
			(xy 240.03 59.69) (xy 240.03 66.04)
		)
		(stroke
			(width 0)
			(type default)
		)
	)
	(wire
		(pts
			(xy 278.13 129.54) (xy 283.21 129.54)
		)
		(stroke
			(width 0)
			(type default)
		)
	)
	(bus
		(pts
			(xy 311.15 173.99) (xy 311.15 179.07)
		)
		(stroke
			(width 0)
			(type default)
		)
	)
	(wire
		(pts
			(xy 129.54 43.18) (xy 138.43 43.18)
		)
		(stroke
			(width 0)
			(type default)
		)
	)
	(wire
		(pts
			(xy 147.32 50.8) (xy 147.32 53.34)
		)
		(stroke
			(width 0)
			(type default)
		)
	)
	(wire
		(pts
			(xy 176.53 251.46) (xy 176.53 254)
		)
		(stroke
			(width 0)
			(type default)
		)
	)
	(wire
		(pts
			(xy 148.59 73.66) (xy 148.59 76.2)
		)
		(stroke
			(width 0)
			(type default)
		)
	)
	(wire
		(pts
			(xy 229.87 59.69) (xy 229.87 66.04)
		)
		(stroke
			(width 0)
			(type default)
		)
	)
	(wire
		(pts
			(xy 142.24 205.74) (xy 177.8 205.74)
		)
		(stroke
			(width 0)
			(type default)
		)
	)
	(wire
		(pts
			(xy 257.81 59.69) (xy 257.81 66.04)
		)
		(stroke
			(width 0)
			(type default)
		)
	)
	(wire
		(pts
			(xy 173.99 144.78) (xy 176.53 144.78)
		)
		(stroke
			(width 0)
			(type default)
		)
	)
	(wire
		(pts
			(xy 109.22 236.22) (xy 109.22 240.03)
		)
		(stroke
			(width 0)
			(type default)
		)
	)
	(wire
		(pts
			(xy 236.22 203.2) (xy 237.49 203.2)
		)
		(stroke
			(width 0)
			(type default)
		)
	)
	(wire
		(pts
			(xy 214.63 74.93) (xy 214.63 77.47)
		)
		(stroke
			(width 0)
			(type default)
		)
	)
	(wire
		(pts
			(xy 236.22 190.5) (xy 309.88 190.5)
		)
		(stroke
			(width 0)
			(type default)
		)
	)
	(wire
		(pts
			(xy 153.67 74.93) (xy 156.21 74.93)
		)
		(stroke
			(width 0)
			(type default)
		)
	)
	(wire
		(pts
			(xy 166.37 190.5) (xy 166.37 193.04)
		)
		(stroke
			(width 0)
			(type default)
		)
	)
	(wire
		(pts
			(xy 266.7 59.69) (xy 266.7 63.5)
		)
		(stroke
			(width 0)
			(type default)
		)
	)
	(wire
		(pts
			(xy 173.99 67.31) (xy 205.74 67.31)
		)
		(stroke
			(width 0)
			(type default)
		)
	)
	(wire
		(pts
			(xy 176.53 134.62) (xy 176.53 139.7)
		)
		(stroke
			(width 0)
			(type default)
		)
	)
	(bus
		(pts
			(xy 140.97 241.3) (xy 140.97 243.84)
		)
		(stroke
			(width 0)
			(type default)
		)
	)
	(wire
		(pts
			(xy 237.49 195.58) (xy 237.49 198.12)
		)
		(stroke
			(width 0)
			(type default)
		)
	)
	(wire
		(pts
			(xy 236.22 160.02) (xy 259.08 160.02)
		)
		(stroke
			(width 0)
			(type default)
		)
	)
	(wire
		(pts
			(xy 237.49 246.38) (xy 237.49 248.92)
		)
		(stroke
			(width 0)
			(type default)
		)
	)
	(wire
		(pts
			(xy 264.16 217.17) (xy 264.16 220.98)
		)
		(stroke
			(width 0)
			(type default)
		)
	)
	(wire
		(pts
			(xy 165.1 144.78) (xy 168.91 144.78)
		)
		(stroke
			(width 0)
			(type default)
		)
	)
	(wire
		(pts
			(xy 138.43 140.97) (xy 138.43 146.05)
		)
		(stroke
			(width 0)
			(type default)
		)
	)
	(wire
		(pts
			(xy 245.11 226.06) (xy 252.73 226.06)
		)
		(stroke
			(width 0)
			(type default)
		)
	)
	(wire
		(pts
			(xy 283.21 129.54) (xy 283.21 128.27)
		)
		(stroke
			(width 0)
			(type default)
		)
	)
	(wire
		(pts
			(xy 248.92 59.69) (xy 257.81 59.69)
		)
		(stroke
			(width 0)
			(type default)
		)
	)
	(wire
		(pts
			(xy 288.29 63.5) (xy 288.29 59.69)
		)
		(stroke
			(width 0)
			(type default)
		)
	)
	(wire
		(pts
			(xy 156.21 72.39) (xy 153.67 72.39)
		)
		(stroke
			(width 0)
			(type default)
		)
	)
	(wire
		(pts
			(xy 143.51 185.42) (xy 147.32 185.42)
		)
		(stroke
			(width 0)
			(type default)
		)
	)
	(wire
		(pts
			(xy 132.08 160.02) (xy 177.8 160.02)
		)
		(stroke
			(width 0)
			(type default)
		)
	)
	(wire
		(pts
			(xy 185.42 57.15) (xy 185.42 59.69)
		)
		(stroke
			(width 0)
			(type default)
		)
	)
	(wire
		(pts
			(xy 147.32 185.42) (xy 147.32 186.69)
		)
		(stroke
			(width 0)
			(type default)
		)
	)
	(wire
		(pts
			(xy 143.51 231.14) (xy 177.8 231.14)
		)
		(stroke
			(width 0)
			(type default)
		)
	)
	(wire
		(pts
			(xy 105.41 43.18) (xy 111.76 43.18)
		)
		(stroke
			(width 0)
			(type default)
		)
	)
	(wire
		(pts
			(xy 245.11 215.9) (xy 252.73 215.9)
		)
		(stroke
			(width 0)
			(type default)
		)
	)
	(wire
		(pts
			(xy 229.87 77.47) (xy 229.87 71.12)
		)
		(stroke
			(width 0)
			(type default)
		)
	)
	(wire
		(pts
			(xy 120.65 62.23) (xy 111.76 62.23)
		)
		(stroke
			(width 0)
			(type default)
		)
	)
	(wire
		(pts
			(xy 236.22 147.32) (xy 237.49 147.32)
		)
		(stroke
			(width 0)
			(type default)
		)
	)
	(wire
		(pts
			(xy 264.16 220.98) (xy 271.78 220.98)
		)
		(stroke
			(width 0)
			(type default)
		)
	)
	(wire
		(pts
			(xy 176.53 223.52) (xy 176.53 220.98)
		)
		(stroke
			(width 0)
			(type default)
		)
	)
	(wire
		(pts
			(xy 257.81 129.54) (xy 257.81 133.35)
		)
		(stroke
			(width 0)
			(type default)
		)
	)
	(wire
		(pts
			(xy 176.53 220.98) (xy 177.8 220.98)
		)
		(stroke
			(width 0)
			(type default)
		)
	)
	(wire
		(pts
			(xy 229.87 59.69) (xy 240.03 59.69)
		)
		(stroke
			(width 0)
			(type default)
		)
	)
	(wire
		(pts
			(xy 173.99 190.5) (xy 177.8 190.5)
		)
		(stroke
			(width 0)
			(type default)
		)
	)
	(bus
		(pts
			(xy 116.84 149.86) (xy 116.84 153.67)
		)
		(stroke
			(width 0)
			(type default)
		)
	)
	(wire
		(pts
			(xy 236.22 180.34) (xy 309.88 180.34)
		)
		(stroke
			(width 0)
			(type default)
		)
	)
	(bus
		(pts
			(xy 140.97 195.58) (xy 140.97 199.39)
		)
		(stroke
			(width 0)
			(type default)
		)
	)
	(wire
		(pts
			(xy 156.21 64.77) (xy 148.59 64.77)
		)
		(stroke
			(width 0)
			(type default)
		)
	)
	(wire
		(pts
			(xy 267.97 129.54) (xy 267.97 133.35)
		)
		(stroke
			(width 0)
			(type default)
		)
	)
	(bus
		(pts
			(xy 111.76 148.59) (xy 115.57 148.59)
		)
		(stroke
			(width 0)
			(type default)
		)
	)
	(wire
		(pts
			(xy 100.33 236.22) (xy 109.22 236.22)
		)
		(stroke
			(width 0)
			(type default)
		)
	)
	(wire
		(pts
			(xy 177.8 251.46) (xy 176.53 251.46)
		)
		(stroke
			(width 0)
			(type default)
		)
	)
	(wire
		(pts
			(xy 177.8 139.7) (xy 176.53 139.7)
		)
		(stroke
			(width 0)
			(type default)
		)
	)
	(wire
		(pts
			(xy 111.76 62.23) (xy 111.76 43.18)
		)
		(stroke
			(width 0)
			(type default)
		)
	)
	(wire
		(pts
			(xy 165.1 175.26) (xy 168.91 175.26)
		)
		(stroke
			(width 0)
			(type default)
		)
	)
	(wire
		(pts
			(xy 118.11 154.94) (xy 144.78 154.94)
		)
		(stroke
			(width 0)
			(type default)
		)
	)
	(wire
		(pts
			(xy 170.18 128.27) (xy 170.18 129.54)
		)
		(stroke
			(width 0)
			(type default)
		)
	)
	(wire
		(pts
			(xy 165.1 170.18) (xy 165.1 167.64)
		)
		(stroke
			(width 0)
			(type default)
		)
	)
	(wire
		(pts
			(xy 116.84 226.06) (xy 107.95 226.06)
		)
		(stroke
			(width 0)
			(type default)
		)
	)
	(wire
		(pts
			(xy 236.22 208.28) (xy 240.03 208.28)
		)
		(stroke
			(width 0)
			(type default)
		)
	)
	(wire
		(pts
			(xy 248.92 137.16) (xy 252.73 137.16)
		)
		(stroke
			(width 0)
			(type default)
		)
	)
	(wire
		(pts
			(xy 100.33 238.76) (xy 107.95 238.76)
		)
		(stroke
			(width 0)
			(type default)
		)
	)
	(wire
		(pts
			(xy 83.82 40.64) (xy 83.82 43.18)
		)
		(stroke
			(width 0)
			(type default)
		)
	)
	(bus
		(pts
			(xy 93.98 231.14) (xy 96.52 231.14)
		)
		(stroke
			(width 0)
			(type default)
		)
	)
	(wire
		(pts
			(xy 176.53 144.78) (xy 177.8 144.78)
		)
		(stroke
			(width 0)
			(type default)
		)
	)
	(wire
		(pts
			(xy 248.92 71.12) (xy 248.92 77.47)
		)
		(stroke
			(width 0)
			(type default)
		)
	)
	(wire
		(pts
			(xy 115.57 43.18) (xy 119.38 43.18)
		)
		(stroke
			(width 0)
			(type default)
		)
	)
	(wire
		(pts
			(xy 245.11 236.22) (xy 264.16 236.22)
		)
		(stroke
			(width 0)
			(type default)
		)
	)
	(wire
		(pts
			(xy 264.16 208.28) (xy 275.59 208.28)
		)
		(stroke
			(width 0)
			(type default)
		)
	)
	(wire
		(pts
			(xy 266.7 68.58) (xy 266.7 71.12)
		)
		(stroke
			(width 0)
			(type default)
		)
	)
	(wire
		(pts
			(xy 153.67 134.62) (xy 157.48 134.62)
		)
		(stroke
			(width 0)
			(type default)
		)
	)
	(wire
		(pts
			(xy 236.22 241.3) (xy 240.03 241.3)
		)
		(stroke
			(width 0)
			(type default)
		)
	)
	(wire
		(pts
			(xy 118.11 160.02) (xy 132.08 160.02)
		)
		(stroke
			(width 0)
			(type default)
		)
	)
	(wire
		(pts
			(xy 236.22 175.26) (xy 309.88 175.26)
		)
		(stroke
			(width 0)
			(type default)
		)
	)
	(wire
		(pts
			(xy 162.56 129.54) (xy 170.18 129.54)
		)
		(stroke
			(width 0)
			(type default)
		)
	)
	(wire
		(pts
			(xy 236.22 226.06) (xy 240.03 226.06)
		)
		(stroke
			(width 0)
			(type default)
		)
	)
	(bus
		(pts
			(xy 139.7 194.31) (xy 140.97 195.58)
		)
		(stroke
			(width 0)
			(type default)
		)
	)
	(bus
		(pts
			(xy 140.97 226.06) (xy 140.97 228.6)
		)
		(stroke
			(width 0)
			(type default)
		)
	)
	(bus
		(pts
			(xy 140.97 241.3) (xy 139.7 240.03)
		)
		(stroke
			(width 0)
			(type default)
		)
	)
	(wire
		(pts
			(xy 214.63 66.04) (xy 214.63 67.31)
		)
		(stroke
			(width 0)
			(type default)
		)
	)
	(wire
		(pts
			(xy 165.1 165.1) (xy 168.91 165.1)
		)
		(stroke
			(width 0)
			(type default)
		)
	)
	(wire
		(pts
			(xy 237.49 198.12) (xy 237.49 199.39)
		)
		(stroke
			(width 0)
			(type default)
		)
	)
	(wire
		(pts
			(xy 143.51 243.84) (xy 177.8 243.84)
		)
		(stroke
			(width 0)
			(type default)
		)
	)
	(wire
		(pts
			(xy 285.75 166.37) (xy 285.75 167.64)
		)
		(stroke
			(width 0)
			(type default)
		)
	)
	(wire
		(pts
			(xy 165.1 144.78) (xy 165.1 149.86)
		)
		(stroke
			(width 0)
			(type default)
		)
	)
	(wire
		(pts
			(xy 143.51 228.6) (xy 177.8 228.6)
		)
		(stroke
			(width 0)
			(type default)
		)
	)
	(wire
		(pts
			(xy 266.7 76.2) (xy 266.7 77.47)
		)
		(stroke
			(width 0)
			(type default)
		)
	)
	(wire
		(pts
			(xy 242.57 142.24) (xy 252.73 142.24)
		)
		(stroke
			(width 0)
			(type default)
		)
	)
	(wire
		(pts
			(xy 173.99 193.04) (xy 177.8 193.04)
		)
		(stroke
			(width 0)
			(type default)
		)
	)
	(wire
		(pts
			(xy 147.32 43.18) (xy 154.94 43.18)
		)
		(stroke
			(width 0)
			(type default)
		)
	)
	(wire
		(pts
			(xy 135.89 62.23) (xy 135.89 64.77)
		)
		(stroke
			(width 0)
			(type default)
		)
	)
	(wire
		(pts
			(xy 166.37 220.98) (xy 168.91 220.98)
		)
		(stroke
			(width 0)
			(type default)
		)
	)
	(wire
		(pts
			(xy 236.22 231.14) (xy 240.03 231.14)
		)
		(stroke
			(width 0)
			(type default)
		)
	)
	(bus
		(pts
			(xy 311.15 158.75) (xy 311.15 171.45)
		)
		(stroke
			(width 0)
			(type default)
		)
	)
	(wire
		(pts
			(xy 129.54 62.23) (xy 135.89 62.23)
		)
		(stroke
			(width 0)
			(type default)
		)
	)
	(wire
		(pts
			(xy 236.22 152.4) (xy 237.49 152.4)
		)
		(stroke
			(width 0)
			(type default)
		)
	)
	(bus
		(pts
			(xy 312.42 152.4) (xy 316.23 152.4)
		)
		(stroke
			(width 0)
			(type default)
		)
	)
	(wire
		(pts
			(xy 132.08 140.97) (xy 138.43 140.97)
		)
		(stroke
			(width 0)
			(type default)
		)
	)
	(wire
		(pts
			(xy 264.16 208.28) (xy 264.16 212.09)
		)
		(stroke
			(width 0)
			(type default)
		)
	)
	(wire
		(pts
			(xy 250.19 208.28) (xy 250.19 210.82)
		)
		(stroke
			(width 0)
			(type default)
		)
	)
	(wire
		(pts
			(xy 181.61 57.15) (xy 185.42 57.15)
		)
		(stroke
			(width 0)
			(type default)
		)
	)
	(wire
		(pts
			(xy 166.37 193.04) (xy 168.91 193.04)
		)
		(stroke
			(width 0)
			(type default)
		)
	)
	(bus
		(pts
			(xy 311.15 153.67) (xy 311.15 156.21)
		)
		(stroke
			(width 0)
			(type default)
		)
	)
	(wire
		(pts
			(xy 237.49 199.39) (xy 237.49 200.66)
		)
		(stroke
			(width 0)
			(type default)
		)
	)
	(wire
		(pts
			(xy 237.49 199.39) (xy 252.73 199.39)
		)
		(stroke
			(width 0)
			(type default)
		)
	)
	(wire
		(pts
			(xy 285.75 157.48) (xy 309.88 157.48)
		)
		(stroke
			(width 0)
			(type default)
		)
	)
	(bus
		(pts
			(xy 311.15 179.07) (xy 311.15 181.61)
		)
		(stroke
			(width 0)
			(type default)
		)
	)
	(wire
		(pts
			(xy 144.78 151.13) (xy 144.78 154.94)
		)
		(stroke
			(width 0)
			(type default)
		)
	)
	(wire
		(pts
			(xy 170.18 133.35) (xy 170.18 134.62)
		)
		(stroke
			(width 0)
			(type default)
		)
	)
	(wire
		(pts
			(xy 109.22 245.11) (xy 109.22 246.38)
		)
		(stroke
			(width 0)
			(type default)
		)
	)
	(wire
		(pts
			(xy 115.57 41.91) (xy 115.57 43.18)
		)
		(stroke
			(width 0)
			(type default)
		)
	)
	(bus
		(pts
			(xy 97.79 233.68) (xy 97.79 236.22)
		)
		(stroke
			(width 0)
			(type default)
		)
	)
	(wire
		(pts
			(xy 240.03 59.69) (xy 248.92 59.69)
		)
		(stroke
			(width 0)
			(type default)
		)
	)
	(wire
		(pts
			(xy 194.31 59.69) (xy 205.74 59.69)
		)
		(stroke
			(width 0)
			(type default)
		)
	)
	(bus
		(pts
			(xy 311.15 156.21) (xy 311.15 158.75)
		)
		(stroke
			(width 0)
			(type default)
		)
	)
	(wire
		(pts
			(xy 257.81 138.43) (xy 257.81 140.97)
		)
		(stroke
			(width 0)
			(type default)
		)
	)
	(bus
		(pts
			(xy 140.97 199.39) (xy 140.97 201.93)
		)
		(stroke
			(width 0)
			(type default)
		)
	)
	(bus
		(pts
			(xy 140.97 204.47) (xy 140.97 207.01)
		)
		(stroke
			(width 0)
			(type default)
		)
	)
	(wire
		(pts
			(xy 267.97 129.54) (xy 273.05 129.54)
		)
		(stroke
			(width 0)
			(type default)
		)
	)
	(wire
		(pts
			(xy 138.43 50.8) (xy 138.43 53.34)
		)
		(stroke
			(width 0)
			(type default)
		)
	)
	(wire
		(pts
			(xy 257.81 71.12) (xy 257.81 77.47)
		)
		(stroke
			(width 0)
			(type default)
		)
	)
	(wire
		(pts
			(xy 153.67 74.93) (xy 153.67 76.2)
		)
		(stroke
			(width 0)
			(type default)
		)
	)
	(wire
		(pts
			(xy 288.29 57.15) (xy 288.29 59.69)
		)
		(stroke
			(width 0)
			(type default)
		)
	)
	(wire
		(pts
			(xy 173.99 72.39) (xy 175.26 72.39)
		)
		(stroke
			(width 0)
			(type default)
		)
	)
	(wire
		(pts
			(xy 109.22 236.22) (xy 177.8 236.22)
		)
		(stroke
			(width 0)
			(type default)
		)
	)
	(wire
		(pts
			(xy 266.7 160.02) (xy 266.7 161.29)
		)
		(stroke
			(width 0)
			(type default)
		)
	)
	(wire
		(pts
			(xy 153.67 129.54) (xy 153.67 134.62)
		)
		(stroke
			(width 0)
			(type default)
		)
	)
	(wire
		(pts
			(xy 214.63 59.69) (xy 229.87 59.69)
		)
		(stroke
			(width 0)
			(type default)
		)
	)
	(wire
		(pts
			(xy 236.22 182.88) (xy 309.88 182.88)
		)
		(stroke
			(width 0)
			(type default)
		)
	)
	(wire
		(pts
			(xy 129.54 62.23) (xy 129.54 64.77)
		)
		(stroke
			(width 0)
			(type default)
		)
	)
	(wire
		(pts
			(xy 148.59 64.77) (xy 148.59 68.58)
		)
		(stroke
			(width 0)
			(type default)
		)
	)
	(bus
		(pts
			(xy 140.97 201.93) (xy 140.97 204.47)
		)
		(stroke
			(width 0)
			(type default)
		)
	)
	(wire
		(pts
			(xy 83.82 43.18) (xy 93.98 43.18)
		)
		(stroke
			(width 0)
			(type default)
		)
	)
	(wire
		(pts
			(xy 177.8 149.86) (xy 176.53 149.86)
		)
		(stroke
			(width 0)
			(type default)
		)
	)
	(wire
		(pts
			(xy 154.94 165.1) (xy 165.1 165.1)
		)
		(stroke
			(width 0)
			(type default)
		)
	)
	(wire
		(pts
			(xy 236.22 129.54) (xy 257.81 129.54)
		)
		(stroke
			(width 0)
			(type default)
		)
	)
	(wire
		(pts
			(xy 135.89 62.23) (xy 156.21 62.23)
		)
		(stroke
			(width 0)
			(type default)
		)
	)
	(wire
		(pts
			(xy 240.03 71.12) (xy 240.03 77.47)
		)
		(stroke
			(width 0)
			(type default)
		)
	)
	(wire
		(pts
			(xy 288.29 71.12) (xy 288.29 77.47)
		)
		(stroke
			(width 0)
			(type default)
		)
	)
	(wire
		(pts
			(xy 205.74 67.31) (xy 214.63 67.31)
		)
		(stroke
			(width 0)
			(type default)
		)
	)
	(wire
		(pts
			(xy 266.7 166.37) (xy 266.7 167.64)
		)
		(stroke
			(width 0)
			(type default)
		)
	)
	(wire
		(pts
			(xy 236.22 167.64) (xy 237.49 167.64)
		)
		(stroke
			(width 0)
			(type default)
		)
	)
	(wire
		(pts
			(xy 173.99 220.98) (xy 176.53 220.98)
		)
		(stroke
			(width 0)
			(type default)
		)
	)
	(bus
		(pts
			(xy 138.43 194.31) (xy 139.7 194.31)
		)
		(stroke
			(width 0)
			(type default)
		)
	)
	(bus
		(pts
			(xy 116.84 153.67) (xy 116.84 156.21)
		)
		(stroke
			(width 0)
			(type default)
		)
	)
	(wire
		(pts
			(xy 138.43 140.97) (xy 144.78 140.97)
		)
		(stroke
			(width 0)
			(type default)
		)
	)
	(wire
		(pts
			(xy 236.22 137.16) (xy 243.84 137.16)
		)
		(stroke
			(width 0)
			(type default)
		)
	)
	(wire
		(pts
			(xy 205.74 59.69) (xy 205.74 60.96)
		)
		(stroke
			(width 0)
			(type default)
		)
	)
	(wire
		(pts
			(xy 173.99 175.26) (xy 177.8 175.26)
		)
		(stroke
			(width 0)
			(type default)
		)
	)
	(wire
		(pts
			(xy 111.76 43.18) (xy 115.57 43.18)
		)
		(stroke
			(width 0)
			(type default)
		)
	)
	(wire
		(pts
			(xy 276.86 166.37) (xy 276.86 167.64)
		)
		(stroke
			(width 0)
			(type default)
		)
	)
	(wire
		(pts
			(xy 173.99 149.86) (xy 176.53 149.86)
		)
		(stroke
			(width 0)
			(type default)
		)
	)
	(wire
		(pts
			(xy 173.99 57.15) (xy 176.53 57.15)
		)
		(stroke
			(width 0)
			(type default)
		)
	)
	(wire
		(pts
			(xy 165.1 170.18) (xy 168.91 170.18)
		)
		(stroke
			(width 0)
			(type default)
		)
	)
	(wire
		(pts
			(xy 147.32 191.77) (xy 147.32 193.04)
		)
		(stroke
			(width 0)
			(type default)
		)
	)
	(wire
		(pts
			(xy 165.1 167.64) (xy 165.1 165.1)
		)
		(stroke
			(width 0)
			(type default)
		)
	)
	(wire
		(pts
			(xy 237.49 165.1) (xy 237.49 167.64)
		)
		(stroke
			(width 0)
			(type default)
		)
	)
	(bus
		(pts
			(xy 311.15 181.61) (xy 311.15 186.69)
		)
		(stroke
			(width 0)
			(type default)
		)
	)
	(wire
		(pts
			(xy 267.97 138.43) (xy 267.97 140.97)
		)
		(stroke
			(width 0)
			(type default)
		)
	)
	(wire
		(pts
			(xy 237.49 200.66) (xy 237.49 203.2)
		)
		(stroke
			(width 0)
			(type default)
		)
	)
	(wire
		(pts
			(xy 166.37 190.5) (xy 168.91 190.5)
		)
		(stroke
			(width 0)
			(type default)
		)
	)
	(wire
		(pts
			(xy 176.53 134.62) (xy 177.8 134.62)
		)
		(stroke
			(width 0)
			(type default)
		)
	)
	(wire
		(pts
			(xy 135.89 69.85) (xy 135.89 72.39)
		)
		(stroke
			(width 0)
			(type default)
		)
	)
	(wire
		(pts
			(xy 107.95 238.76) (xy 177.8 238.76)
		)
		(stroke
			(width 0)
			(type default)
		)
	)
	(wire
		(pts
			(xy 250.19 208.28) (xy 264.16 208.28)
		)
		(stroke
			(width 0)
			(type default)
		)
	)
	(bus
		(pts
			(xy 311.15 189.23) (xy 311.15 186.69)
		)
		(stroke
			(width 0)
			(type default)
		)
	)
	(wire
		(pts
			(xy 288.29 59.69) (xy 289.56 59.69)
		)
		(stroke
			(width 0)
			(type default)
		)
	)
	(wire
		(pts
			(xy 166.37 193.04) (xy 156.21 193.04)
		)
		(stroke
			(width 0)
			(type default)
		)
	)
	(wire
		(pts
			(xy 259.08 160.02) (xy 266.7 160.02)
		)
		(stroke
			(width 0)
			(type default)
		)
	)
	(wire
		(pts
			(xy 170.18 129.54) (xy 177.8 129.54)
		)
		(stroke
			(width 0)
			(type default)
		)
	)
	(wire
		(pts
			(xy 142.24 203.2) (xy 177.8 203.2)
		)
		(stroke
			(width 0)
			(type default)
		)
	)
	(wire
		(pts
			(xy 236.22 246.38) (xy 237.49 246.38)
		)
		(stroke
			(width 0)
			(type default)
		)
	)
	(wire
		(pts
			(xy 147.32 43.18) (xy 147.32 45.72)
		)
		(stroke
			(width 0)
			(type default)
		)
	)
	(wire
		(pts
			(xy 245.11 210.82) (xy 250.19 210.82)
		)
		(stroke
			(width 0)
			(type default)
		)
	)
	(wire
		(pts
			(xy 119.38 43.18) (xy 129.54 43.18)
		)
		(stroke
			(width 0)
			(type default)
		)
	)
	(wire
		(pts
			(xy 173.99 59.69) (xy 185.42 59.69)
		)
		(stroke
			(width 0)
			(type default)
		)
	)
	(wire
		(pts
			(xy 165.1 170.18) (xy 165.1 175.26)
		)
		(stroke
			(width 0)
			(type default)
		)
	)
	(wire
		(pts
			(xy 153.67 129.54) (xy 157.48 129.54)
		)
		(stroke
			(width 0)
			(type default)
		)
	)
	(bus
		(pts
			(xy 138.43 224.79) (xy 139.7 224.79)
		)
		(stroke
			(width 0)
			(type default)
		)
	)
	(wire
		(pts
			(xy 177.8 223.52) (xy 176.53 223.52)
		)
		(stroke
			(width 0)
			(type default)
		)
	)
	(wire
		(pts
			(xy 138.43 157.48) (xy 177.8 157.48)
		)
		(stroke
			(width 0)
			(type default)
		)
	)
	(wire
		(pts
			(xy 107.95 226.06) (xy 107.95 227.33)
		)
		(stroke
			(width 0)
			(type default)
		)
	)
	(wire
		(pts
			(xy 236.22 200.66) (xy 237.49 200.66)
		)
		(stroke
			(width 0)
			(type default)
		)
	)
	(wire
		(pts
			(xy 176.53 140.97) (xy 176.53 144.78)
		)
		(stroke
			(width 0)
			(type default)
		)
	)
	(wire
		(pts
			(xy 138.43 151.13) (xy 138.43 157.48)
		)
		(stroke
			(width 0)
			(type default)
		)
	)
	(wire
		(pts
			(xy 214.63 67.31) (xy 214.63 69.85)
		)
		(stroke
			(width 0)
			(type default)
		)
	)
	(wire
		(pts
			(xy 236.22 210.82) (xy 240.03 210.82)
		)
		(stroke
			(width 0)
			(type default)
		)
	)
	(wire
		(pts
			(xy 259.08 166.37) (xy 259.08 167.64)
		)
		(stroke
			(width 0)
			(type default)
		)
	)
	(wire
		(pts
			(xy 173.99 165.1) (xy 177.8 165.1)
		)
		(stroke
			(width 0)
			(type default)
		)
	)
	(wire
		(pts
			(xy 119.38 43.18) (xy 119.38 45.72)
		)
		(stroke
			(width 0)
			(type default)
		)
	)
	(wire
		(pts
			(xy 285.75 157.48) (xy 285.75 161.29)
		)
		(stroke
			(width 0)
			(type default)
		)
	)
	(bus
		(pts
			(xy 97.79 232.41) (xy 97.79 233.68)
		)
		(stroke
			(width 0)
			(type default)
		)
	)
	(wire
		(pts
			(xy 147.32 185.42) (xy 168.91 185.42)
		)
		(stroke
			(width 0)
			(type default)
		)
	)
	(wire
		(pts
			(xy 185.42 59.69) (xy 189.23 59.69)
		)
		(stroke
			(width 0)
			(type default)
		)
	)
	(wire
		(pts
			(xy 236.22 172.72) (xy 309.88 172.72)
		)
		(stroke
			(width 0)
			(type default)
		)
	)
	(wire
		(pts
			(xy 125.73 62.23) (xy 129.54 62.23)
		)
		(stroke
			(width 0)
			(type default)
		)
	)
	(wire
		(pts
			(xy 266.7 59.69) (xy 276.86 59.69)
		)
		(stroke
			(width 0)
			(type default)
		)
	)
	(wire
		(pts
			(xy 138.43 43.18) (xy 138.43 45.72)
		)
		(stroke
			(width 0)
			(type default)
		)
	)
	(wire
		(pts
			(xy 165.1 149.86) (xy 168.91 149.86)
		)
		(stroke
			(width 0)
			(type default)
		)
	)
	(wire
		(pts
			(xy 237.49 254) (xy 237.49 256.54)
		)
		(stroke
			(width 0)
			(type default)
		)
	)
	(bus
		(pts
			(xy 311.15 171.45) (xy 311.15 173.99)
		)
		(stroke
			(width 0)
			(type default)
		)
	)
	(wire
		(pts
			(xy 154.94 57.15) (xy 156.21 57.15)
		)
		(stroke
			(width 0)
			(type default)
		)
	)
	(wire
		(pts
			(xy 132.08 140.97) (xy 132.08 146.05)
		)
		(stroke
			(width 0)
			(type default)
		)
	)
	(bus
		(pts
			(xy 139.7 224.79) (xy 140.97 226.06)
		)
		(stroke
			(width 0)
			(type default)
		)
	)
	(wire
		(pts
			(xy 236.22 187.96) (xy 309.88 187.96)
		)
		(stroke
			(width 0)
			(type default)
		)
	)
	(bus
		(pts
			(xy 116.84 156.21) (xy 116.84 158.75)
		)
		(stroke
			(width 0)
			(type default)
		)
	)
	(wire
		(pts
			(xy 288.29 66.04) (xy 288.29 63.5)
		)
		(stroke
			(width 0)
			(type default)
		)
	)
	(wire
		(pts
			(xy 138.43 43.18) (xy 147.32 43.18)
		)
		(stroke
			(width 0)
			(type default)
		)
	)
	(wire
		(pts
			(xy 129.54 50.8) (xy 129.54 53.34)
		)
		(stroke
			(width 0)
			(type default)
		)
	)
	(wire
		(pts
			(xy 289.56 63.5) (xy 288.29 63.5)
		)
		(stroke
			(width 0)
			(type default)
		)
	)
	(wire
		(pts
			(xy 236.22 165.1) (xy 237.49 165.1)
		)
		(stroke
			(width 0)
			(type default)
		)
	)
	(wire
		(pts
			(xy 143.51 246.38) (xy 177.8 246.38)
		)
		(stroke
			(width 0)
			(type default)
		)
	)
	(wire
		(pts
			(xy 259.08 160.02) (xy 259.08 161.29)
		)
		(stroke
			(width 0)
			(type default)
		)
	)
	(wire
		(pts
			(xy 248.92 59.69) (xy 248.92 66.04)
		)
		(stroke
			(width 0)
			(type default)
		)
	)
	(wire
		(pts
			(xy 119.38 50.8) (xy 119.38 53.34)
		)
		(stroke
			(width 0)
			(type default)
		)
	)
	(wire
		(pts
			(xy 170.18 134.62) (xy 176.53 134.62)
		)
		(stroke
			(width 0)
			(type default)
		)
	)
	(wire
		(pts
			(xy 93.98 43.18) (xy 100.33 43.18)
		)
		(stroke
			(width 0)
			(type default)
		)
	)
	(bus
		(pts
			(xy 138.43 240.03) (xy 139.7 240.03)
		)
		(stroke
			(width 0)
			(type default)
		)
	)
	(wire
		(pts
			(xy 245.11 208.28) (xy 250.19 208.28)
		)
		(stroke
			(width 0)
			(type default)
		)
	)
	(wire
		(pts
			(xy 129.54 43.18) (xy 129.54 45.72)
		)
		(stroke
			(width 0)
			(type default)
		)
	)
	(wire
		(pts
			(xy 257.81 59.69) (xy 266.7 59.69)
		)
		(stroke
			(width 0)
			(type default)
		)
	)
	(wire
		(pts
			(xy 162.56 134.62) (xy 170.18 134.62)
		)
		(stroke
			(width 0)
			(type default)
		)
	)
	(wire
		(pts
			(xy 118.11 157.48) (xy 138.43 157.48)
		)
		(stroke
			(width 0)
			(type default)
		)
	)
	(wire
		(pts
			(xy 242.57 132.08) (xy 252.73 132.08)
		)
		(stroke
			(width 0)
			(type default)
		)
	)
	(wire
		(pts
			(xy 257.81 129.54) (xy 267.97 129.54)
		)
		(stroke
			(width 0)
			(type default)
		)
	)
	(wire
		(pts
			(xy 267.97 127) (xy 267.97 129.54)
		)
		(stroke
			(width 0)
			(type default)
		)
	)
	(wire
		(pts
			(xy 242.57 152.4) (xy 252.73 152.4)
		)
		(stroke
			(width 0)
			(type default)
		)
	)
	(wire
		(pts
			(xy 266.7 160.02) (xy 309.88 160.02)
		)
		(stroke
			(width 0)
			(type default)
		)
	)
	(wire
		(pts
			(xy 154.94 43.18) (xy 154.94 57.15)
		)
		(stroke
			(width 0)
			(type default)
		)
	)
	(bus
		(pts
			(xy 96.52 231.14) (xy 97.79 232.41)
		)
		(stroke
			(width 0)
			(type default)
		)
	)
	(wire
		(pts
			(xy 173.99 170.18) (xy 177.8 170.18)
		)
		(stroke
			(width 0)
			(type default)
		)
	)
	(bus
		(pts
			(xy 311.15 153.67) (xy 312.42 152.4)
		)
		(stroke
			(width 0)
			(type default)
		)
	)
	(wire
		(pts
			(xy 142.24 208.28) (xy 177.8 208.28)
		)
		(stroke
			(width 0)
			(type default)
		)
	)
	(wire
		(pts
			(xy 276.86 157.48) (xy 285.75 157.48)
		)
		(stroke
			(width 0)
			(type default)
		)
	)
	(wire
		(pts
			(xy 214.63 59.69) (xy 214.63 60.96)
		)
		(stroke
			(width 0)
			(type default)
		)
	)
	(wire
		(pts
			(xy 93.98 41.91) (xy 93.98 43.18)
		)
		(stroke
			(width 0)
			(type default)
		)
	)
	(wire
		(pts
			(xy 132.08 151.13) (xy 132.08 160.02)
		)
		(stroke
			(width 0)
			(type default)
		)
	)
	(wire
		(pts
			(xy 142.24 200.66) (xy 177.8 200.66)
		)
		(stroke
			(width 0)
			(type default)
		)
	)
	(wire
		(pts
			(xy 144.78 140.97) (xy 176.53 140.97)
		)
		(stroke
			(width 0)
			(type default)
		)
	)
	(label "TPS_3V3"
		(at 154.94 165.1 0)
		(effects
			(font
				(size 1.27 1.27)
			)
			(justify left bottom)
		)
	)
	(label "TPS_3V3"
		(at 156.21 193.04 0)
		(effects
			(font
				(size 1.27 1.27)
			)
			(justify left bottom)
		)
	)
	(label "USB3.D_A_P"
		(at 297.18 172.72 0)
		(effects
			(font
				(size 1.27 1.27)
			)
			(justify left bottom)
		)
	)
	(label "I2C1.SDA"
		(at 128.27 154.94 180)
		(effects
			(font
				(size 1.27 1.27)
			)
			(justify right bottom)
		)
	)
	(label "LSX_1.LSX_R2P"
		(at 146.05 228.6 0)
		(effects
			(font
				(size 1.27 1.27)
			)
			(justify left bottom)
		)
	)
	(label "USB_RP.D-"
		(at 146.05 246.38 0)
		(effects
			(font
				(size 1.27 1.27)
			)
			(justify left bottom)
		)
	)
	(label "SMPS_LDO"
		(at 190.5 72.39 180)
		(effects
			(font
				(size 1.27 1.27)
			)
			(justify right bottom)
		)
	)
	(label "SMPS_LDO"
		(at 156.21 64.77 180)
		(effects
			(font
				(size 1.27 1.27)
			)
			(justify right bottom)
		)
	)
	(label "TPS_3V3"
		(at 275.59 208.28 180)
		(effects
			(font
				(size 1.27 1.27)
			)
			(justify right bottom)
		)
	)
	(label "USB3.CC2"
		(at 297.18 160.02 0)
		(effects
			(font
				(size 1.27 1.27)
			)
			(justify left bottom)
		)
	)
	(label "TB_FLASH.~{CE}"
		(at 148.59 208.28 0)
		(effects
			(font
				(size 1.27 1.27)
			)
			(justify left bottom)
		)
	)
	(label "USB3.D_B_N"
		(at 297.18 182.88 0)
		(effects
			(font
				(size 1.27 1.27)
			)
			(justify left bottom)
		)
	)
	(label "USB3.D_A_N"
		(at 297.18 175.26 0)
		(effects
			(font
				(size 1.27 1.27)
			)
			(justify left bottom)
		)
	)
	(label "I2C1.SCL"
		(at 128.27 157.48 180)
		(effects
			(font
				(size 1.27 1.27)
			)
			(justify right bottom)
		)
	)
	(label "USB3.SBU1"
		(at 297.18 187.96 0)
		(effects
			(font
				(size 1.27 1.27)
			)
			(justify left bottom)
		)
	)
	(label "USB_RP.D+"
		(at 146.05 243.84 0)
		(effects
			(font
				(size 1.27 1.27)
			)
			(justify left bottom)
		)
	)
	(label "USB3.SBU2"
		(at 297.18 190.5 0)
		(effects
			(font
				(size 1.27 1.27)
			)
			(justify left bottom)
		)
	)
	(label "AUX.-"
		(at 101.6 238.76 0)
		(effects
			(font
				(size 1.27 1.27)
			)
			(justify left bottom)
		)
	)
	(label "TB_FLASH.MISO"
		(at 148.59 205.74 0)
		(effects
			(font
				(size 1.27 1.27)
			)
			(justify left bottom)
		)
	)
	(label "I2C1.IRQ"
		(at 128.27 160.02 180)
		(effects
			(font
				(size 1.27 1.27)
			)
			(justify right bottom)
		)
	)
	(label "AUX.+"
		(at 101.6 236.22 0)
		(effects
			(font
				(size 1.27 1.27)
			)
			(justify left bottom)
		)
	)
	(label "LSX_1.LSX_P2R"
		(at 146.05 231.14 0)
		(effects
			(font
				(size 1.27 1.27)
			)
			(justify left bottom)
		)
	)
	(label "TPS_3V3"
		(at 236.22 137.16 0)
		(effects
			(font
				(size 1.27 1.27)
			)
			(justify left bottom)
		)
	)
	(label "TPS_3V3"
		(at 264.16 236.22 180)
		(effects
			(font
				(size 1.27 1.27)
			)
			(justify right bottom)
		)
	)
	(label "TB_FLASH.CLK"
		(at 148.59 200.66 0)
		(effects
			(font
				(size 1.27 1.27)
			)
			(justify left bottom)
		)
	)
	(label "TB_FLASH.MOSI"
		(at 148.59 203.2 0)
		(effects
			(font
				(size 1.27 1.27)
			)
			(justify left bottom)
		)
	)
	(label "USB3.D_B_P"
		(at 297.18 180.34 0)
		(effects
			(font
				(size 1.27 1.27)
			)
			(justify left bottom)
		)
	)
	(label "USB3.CC1"
		(at 297.18 157.48 0)
		(effects
			(font
				(size 1.27 1.27)
			)
			(justify left bottom)
		)
	)
	(label "TPS_3V3"
		(at 116.84 226.06 180)
		(effects
			(font
				(size 1.27 1.27)
			)
			(justify right bottom)
		)
	)
	(hierarchical_label "USB_RP{USB}"
		(shape bidirectional)
		(at 138.43 240.03 180)
		(effects
			(font
				(size 1.27 1.27)
			)
			(justify right)
		)
	)
	(hierarchical_label "RESET_N"
		(shape output)
		(at 271.78 220.98 0)
		(effects
			(font
				(size 1.27 1.27)
			)
			(justify left)
		)
	)
	(hierarchical_label "USB3{USB_3.0}"
		(shape bidirectional)
		(at 316.23 152.4 0)
		(effects
			(font
				(size 1.27 1.27)
			)
			(justify left)
		)
	)
	(hierarchical_label "AUX{AUX_TB}"
		(shape bidirectional)
		(at 93.98 231.14 180)
		(effects
			(font
				(size 1.27 1.27)
			)
			(justify right)
		)
	)
	(hierarchical_label "TB_FLASH{SPI}"
		(shape bidirectional)
		(at 138.43 194.31 180)
		(effects
			(font
				(size 1.27 1.27)
			)
			(justify right)
		)
	)
	(hierarchical_label "I2C1{I2C}"
		(shape bidirectional)
		(at 111.76 148.59 180)
		(effects
			(font
				(size 1.27 1.27)
			)
			(justify right)
		)
	)
	(hierarchical_label "HPD"
		(shape output)
		(at 143.51 185.42 180)
		(effects
			(font
				(size 1.27 1.27)
			)
			(justify right)
		)
	)
	(hierarchical_label "LSX_1{LSX}"
		(shape bidirectional)
		(at 138.43 224.79 180)
		(effects
			(font
				(size 1.27 1.27)
			)
			(justify right)
		)
	)
	(rule_area
		(polyline
			(pts
				(xy 121.92 233.68) (xy 111.76 233.68) (xy 111.76 241.3) (xy 121.92 241.3)
			)
			(stroke
				(width 0)
				(type dash)
			)
			(fill
				(type none)
			)
		)
	)
	(rule_area
		(polyline
			(pts
				(xy 167.64 240.03) (xy 144.78 240.03) (xy 144.78 247.65) (xy 167.64 247.65)
			)
			(stroke
				(width 0)
				(type dash)
			)
			(fill
				(type none)
			)
		)
	)
	(netclass_flag ""
		(length 2.54)
		(shape round)
		(at 144.78 247.65 180)
		(effects
			(font
				(size 1.27 1.27)
			)
			(justify right bottom)
		)
		(property "Netclass" "90Ohm-diff_USB2"
			(at 145.796 250.19 0)
			(effects
				(font
					(size 1.27 1.27)
				)
				(justify left)
			)
		)
		(property "Component Class" ""
			(at 198.12 471.17 90)
			(effects
				(font
					(size 1.27 1.27)
					(italic yes)
				)
				(justify right)
			)
		)
	)
	(netclass_flag ""
		(length 2.54)
		(shape round)
		(at 121.92 233.68 270)
		(effects
			(font
				(size 1.27 1.27)
			)
			(justify right bottom)
		)
		(property "Netclass" "85Ohm-diff_USB4"
			(at 125.73 233.68 0)
			(effects
				(font
					(size 1.27 1.27)
				)
				(justify left)
			)
		)
		(property "Component Class" ""
			(at 345.44 180.34 0)
			(effects
				(font
					(size 1.27 1.27)
					(italic yes)
				)
				(justify left)
			)
		)
	)
	(symbol
		(lib_id "antmicropower:GND")
		(at 252.73 215.9 0)
		(unit 1)
		(exclude_from_sim no)
		(in_bom yes)
		(on_board yes)
		(dnp no)
		(property "Reference" "#PWR043"
			(at 252.73 222.25 0)
			(effects
				(font
					(size 1.27 1.27)
				)
				(hide yes)
			)
		)
		(property "Value" "GND"
			(at 252.73 219.71 0)
			(effects
				(font
					(size 1.27 1.27)
				)
			)
		)
		(property "Footprint" ""
			(at 252.73 215.9 0)
			(effects
				(font
					(size 1.27 1.27)
				)
				(hide yes)
			)
		)
		(property "Datasheet" ""
			(at 252.73 215.9 0)
			(effects
				(font
					(size 1.27 1.27)
				)
				(hide yes)
			)
		)
		(property "Description" ""
			(at 252.73 215.9 0)
			(effects
				(font
					(size 1.27 1.27)
				)
				(hide yes)
			)
		)
		(property "Author" "Antmicro"
			(at 261.62 223.52 0)
			(effects
				(font
					(size 1.27 1.27)
					(thickness 0.15)
				)
				(justify left bottom)
				(hide yes)
			)
		)
		(property "License" "Apache-2.0"
			(at 261.62 226.06 0)
			(effects
				(font
					(size 1.27 1.27)
					(thickness 0.15)
				)
				(justify left bottom)
				(hide yes)
			)
		)
		(pin "1"
		)
		(instances
			(project "thunderbolt-gpu-adapter"
				(path ""
					(reference "#PWR055")
					(unit 1)
				)
			)
			(project "thunderbolt-to-10gbe-adapter"
				(path ""
					(reference "#PWR043")
					(unit 1)
				)
			)
		)
	)
	(symbol
		(lib_id "antmicroCapacitors0402:C_1u_0402")
		(at 237.49 132.08 0)
		(unit 1)
		(exclude_from_sim no)
		(in_bom yes)
		(on_board yes)
		(dnp no)
		(property "Reference" "C19"
			(at 242.57 130.81 0)
			(effects
				(font
					(size 1.27 1.27)
					(thickness 0.15)
				)
			)
		)
		(property "Value" "C_1u_0402"
			(at 257.81 142.24 0)
			(effects
				(font
					(size 1.27 1.27)
					(thickness 0.15)
				)
				(justify left bottom)
				(hide yes)
			)
		)
		(property "Footprint" "antmicro-footprints:C_0402_1005Metric"
			(at 257.81 144.78 0)
			(effects
				(font
					(size 1.27 1.27)
					(thickness 0.15)
				)
				(justify left bottom)
				(hide yes)
			)
		)
		(property "Datasheet" "https://product.tdk.com/en/search/capacitor/ceramic/mlcc/info?part_no=C1005X6S1A105K050BC"
			(at 257.81 147.32 0)
			(effects
				(font
					(size 1.27 1.27)
					(thickness 0.15)
				)
				(justify left bottom)
				(hide yes)
			)
		)
		(property "Description" "SMD Multilayer Ceramic Capacitor, 1 µF, 10 V, 0402 [1005 Metric], ± 10%, X6S, C"
			(at 237.49 132.08 0)
			(effects
				(font
					(size 1.27 1.27)
				)
				(hide yes)
			)
		)
		(property "MPN" "C1005X6S1A105K050BC"
			(at 257.81 149.86 0)
			(effects
				(font
					(size 1.27 1.27)
					(thickness 0.15)
				)
				(justify left bottom)
				(hide yes)
			)
		)
		(property "Manufacturer" "TDK"
			(at 257.81 152.4 0)
			(effects
				(font
					(size 1.27 1.27)
					(thickness 0.15)
				)
				(justify left bottom)
				(hide yes)
			)
		)
		(property "License" "Apache-2.0"
			(at 257.81 154.94 0)
			(effects
				(font
					(size 1.27 1.27)
					(thickness 0.15)
				)
				(justify left bottom)
				(hide yes)
			)
		)
		(property "Val" "1u"
			(at 241.935 133.35 0)
			(effects
				(font
					(size 1.27 1.27)
					(thickness 0.15)
				)
			)
		)
		(property "Voltage" ""
			(at 257.81 160.02 0)
			(effects
				(font
					(size 1.27 1.27)
				)
				(justify left bottom)
				(hide yes)
			)
		)
		(property "Dielectric" ""
			(at 257.81 162.56 0)
			(effects
				(font
					(size 1.27 1.27)
				)
				(justify left bottom)
				(hide yes)
			)
		)
		(property "Author" "Antmicro"
			(at 257.81 157.48 0)
			(effects
				(font
					(size 1.27 1.27)
					(thickness 0.15)
				)
				(justify left bottom)
				(hide yes)
			)
		)
		(pin "1"
		)
		(pin "2"
		)
		(instances
			(project "thunderbolt-gpu-adapter"
				(path ""
					(reference "C34")
					(unit 1)
				)
			)
			(project "thunderbolt-to-10gbe-adapter"
				(path ""
					(reference "C19")
					(unit 1)
				)
			)
		)
	)
	(symbol
		(lib_id "antmicropower:GND")
		(at 129.54 72.39 0)
		(unit 1)
		(exclude_from_sim no)
		(in_bom yes)
		(on_board yes)
		(dnp no)
		(property "Reference" "#PWR019"
			(at 129.54 78.74 0)
			(effects
				(font
					(size 1.27 1.27)
				)
				(hide yes)
			)
		)
		(property "Value" "GND"
			(at 129.54 76.2 0)
			(effects
				(font
					(size 1.27 1.27)
				)
			)
		)
		(property "Footprint" ""
			(at 129.54 72.39 0)
			(effects
				(font
					(size 1.27 1.27)
				)
				(hide yes)
			)
		)
		(property "Datasheet" ""
			(at 129.54 72.39 0)
			(effects
				(font
					(size 1.27 1.27)
				)
				(hide yes)
			)
		)
		(property "Description" ""
			(at 129.54 72.39 0)
			(effects
				(font
					(size 1.27 1.27)
				)
				(hide yes)
			)
		)
		(property "Author" "Antmicro"
			(at 138.43 80.01 0)
			(effects
				(font
					(size 1.27 1.27)
					(thickness 0.15)
				)
				(justify left bottom)
				(hide yes)
			)
		)
		(property "License" "Apache-2.0"
			(at 138.43 82.55 0)
			(effects
				(font
					(size 1.27 1.27)
					(thickness 0.15)
				)
				(justify left bottom)
				(hide yes)
			)
		)
		(pin "1"
		)
		(instances
			(project "thunderbolt-to-10gbe-adapter"
				(path ""
					(reference "#PWR019")
					(unit 1)
				)
			)
		)
	)
	(symbol
		(lib_id "antmicroResistors0402:R_1M_0402")
		(at 168.91 220.98 0)
		(unit 1)
		(exclude_from_sim no)
		(in_bom yes)
		(on_board yes)
		(dnp no)
		(fields_autoplaced yes)
		(property "Reference" "R19"
			(at 171.45 214.63 0)
			(effects
				(font
					(size 1.27 1.27)
					(thickness 0.15)
				)
			)
		)
		(property "Value" "R_1M_0402"
			(at 189.23 233.68 0)
			(effects
				(font
					(size 1.27 1.27)
					(thickness 0.15)
				)
				(justify left bottom)
				(hide yes)
			)
		)
		(property "Footprint" "antmicro-footprints:R_0402_1005Metric"
			(at 189.23 236.22 0)
			(effects
				(font
					(size 1.27 1.27)
					(thickness 0.15)
				)
				(justify left bottom)
				(hide yes)
			)
		)
		(property "Datasheet" "https://www.bourns.com/docs/product-datasheets/cr.pdf"
			(at 189.23 238.76 0)
			(effects
				(font
					(size 1.27 1.27)
					(thickness 0.15)
				)
				(justify left bottom)
				(hide yes)
			)
		)
		(property "Description" "SMD Chip Resistor, 1 Mohm, ± 1%, 62.5 mW, 0402 [1005 Metric], Thick Film, General Purpose"
			(at 168.91 220.98 0)
			(effects
				(font
					(size 1.27 1.27)
				)
				(hide yes)
			)
		)
		(property "MPN" "CR0402-FX-1004GLF"
			(at 189.23 241.3 0)
			(effects
				(font
					(size 1.27 1.27)
					(thickness 0.15)
				)
				(justify left bottom)
				(hide yes)
			)
		)
		(property "Manufacturer" "Bourns"
			(at 189.23 243.84 0)
			(effects
				(font
					(size 1.27 1.27)
					(thickness 0.15)
				)
				(justify left bottom)
				(hide yes)
			)
		)
		(property "License" "Apache-2.0"
			(at 189.23 246.38 0)
			(effects
				(font
					(size 1.27 1.27)
					(thickness 0.15)
				)
				(justify left bottom)
				(hide yes)
			)
		)
		(property "Val" "1M"
			(at 171.45 217.17 0)
			(effects
				(font
					(size 1.27 1.27)
					(thickness 0.15)
				)
			)
		)
		(property "Tolerance" "1%"
			(at 189.23 231.14 0)
			(effects
				(font
					(size 1.27 1.27)
				)
				(justify left bottom)
				(hide yes)
			)
		)
		(property "Author" "Antmicro"
			(at 189.23 248.92 0)
			(effects
				(font
					(size 1.27 1.27)
					(thickness 0.15)
				)
				(justify left bottom)
				(hide yes)
			)
		)
		(pin "1"
		)
		(pin "2"
		)
		(instances
			(project "thunderbolt-gpu-adapter"
				(path ""
					(reference "R21")
					(unit 1)
				)
			)
			(project "thunderbolt-to-10gbe-adapter"
				(path ""
					(reference "R19")
					(unit 1)
				)
			)
		)
	)
	(symbol
		(lib_id "antmicropower:GND")
		(at 138.43 53.34 0)
		(unit 1)
		(exclude_from_sim no)
		(in_bom yes)
		(on_board yes)
		(dnp no)
		(property "Reference" "#PWR022"
			(at 138.43 59.69 0)
			(effects
				(font
					(size 1.27 1.27)
				)
				(hide yes)
			)
		)
		(property "Value" "GND"
			(at 138.43 57.15 0)
			(effects
				(font
					(size 1.27 1.27)
				)
			)
		)
		(property "Footprint" ""
			(at 138.43 53.34 0)
			(effects
				(font
					(size 1.27 1.27)
				)
				(hide yes)
			)
		)
		(property "Datasheet" ""
			(at 138.43 53.34 0)
			(effects
				(font
					(size 1.27 1.27)
				)
				(hide yes)
			)
		)
		(property "Description" ""
			(at 138.43 53.34 0)
			(effects
				(font
					(size 1.27 1.27)
				)
				(hide yes)
			)
		)
		(property "Author" "Antmicro"
			(at 147.32 60.96 0)
			(effects
				(font
					(size 1.27 1.27)
					(thickness 0.15)
				)
				(justify left bottom)
				(hide yes)
			)
		)
		(property "License" "Apache-2.0"
			(at 147.32 63.5 0)
			(effects
				(font
					(size 1.27 1.27)
					(thickness 0.15)
				)
				(justify left bottom)
				(hide yes)
			)
		)
		(pin "1"
		)
		(instances
			(project "thunderbolt-to-10gbe-adapter"
				(path ""
					(reference "#PWR022")
					(unit 1)
				)
			)
		)
	)
	(symbol
		(lib_id "antmicroDCDCConverters:MP2386GG")
		(at 156.21 57.15 0)
		(unit 1)
		(exclude_from_sim no)
		(in_bom yes)
		(on_board yes)
		(dnp no)
		(fields_autoplaced yes)
		(property "Reference" "U2"
			(at 165.1 49.53 0)
			(effects
				(font
					(size 1.27 1.27)
					(thickness 0.15)
				)
			)
		)
		(property "Value" "MP2386GG"
			(at 189.23 64.77 0)
			(effects
				(font
					(size 1.27 1.27)
					(thickness 0.15)
				)
				(justify left bottom)
				(hide yes)
			)
		)
		(property "Footprint" "antmicro-footprints:QFN-11_2x2mm_P0.5mm"
			(at 189.23 67.31 0)
			(effects
				(font
					(size 1.27 1.27)
					(thickness 0.15)
				)
				(justify left bottom)
				(hide yes)
			)
		)
		(property "Datasheet" "https://www.monolithicpower.com/en/documentview/productdocument/index/version/2/document_type/Datasheet/lang/en/sku/MP2386GG-Z/document_id/4066/"
			(at 189.23 69.85 0)
			(effects
				(font
					(size 1.27 1.27)
					(thickness 0.15)
				)
				(justify left bottom)
				(hide yes)
			)
		)
		(property "Description" "DC/DC converter"
			(at 156.21 57.15 0)
			(effects
				(font
					(size 1.27 1.27)
				)
				(hide yes)
			)
		)
		(property "Manufacturer" "Monolithic Power Systems"
			(at 189.23 72.39 0)
			(effects
				(font
					(size 1.27 1.27)
					(thickness 0.15)
				)
				(justify left bottom)
				(hide yes)
			)
		)
		(property "MPN" "MP2386GG-P"
			(at 165.1 52.07 0)
			(effects
				(font
					(size 1.27 1.27)
					(thickness 0.15)
				)
			)
		)
		(property "License" "Apache-2.0"
			(at 189.23 80.01 0)
			(effects
				(font
					(size 1.27 1.27)
					(thickness 0.15)
				)
				(justify left bottom)
				(hide yes)
			)
		)
		(property "Author" "Antmicro"
			(at 189.23 77.47 0)
			(effects
				(font
					(size 1.27 1.27)
					(thickness 0.15)
				)
				(justify left bottom)
				(hide yes)
			)
		)
		(pin "1"
		)
		(pin "10"
		)
		(pin "11"
		)
		(pin "2"
		)
		(pin "3"
		)
		(pin "4"
		)
		(pin "5"
		)
		(pin "6"
		)
		(pin "7"
		)
		(pin "8"
		)
		(pin "9"
		)
		(instances
			(project "thunderbolt-to-10gbe-adapter"
				(path ""
					(reference "U2")
					(unit 1)
				)
			)
		)
	)
	(symbol
		(lib_id "antmicroFerriteBeadsandChips:FB_30Z_8.5A_Murata-BLM21SN_0805")
		(at 276.86 59.69 0)
		(mirror x)
		(unit 1)
		(exclude_from_sim no)
		(in_bom yes)
		(on_board yes)
		(dnp no)
		(property "Reference" "FB2"
			(at 279.4 53.975 0)
			(effects
				(font
					(size 1.27 1.27)
					(thickness 0.15)
				)
			)
		)
		(property "Value" "FB_30Z_8.5A_Murata-BLM21SN_0805"
			(at 278.765 56.515 0)
			(effects
				(font
					(size 1.27 1.27)
					(thickness 0.15)
				)
				(hide yes)
			)
		)
		(property "Footprint" "antmicro-footprints:FB_0805_2012Metric"
			(at 290.83 54.61 0)
			(effects
				(font
					(size 1.27 1.27)
					(thickness 0.15)
				)
				(justify left bottom)
				(hide yes)
			)
		)
		(property "Datasheet" "https://www.murata.com/en-sg/products/productdata/8796738977822/ENFA0005.pdf?1519270210000"
			(at 290.83 52.07 0)
			(effects
				(font
					(size 1.27 1.27)
					(thickness 0.15)
				)
				(justify left bottom)
				(hide yes)
			)
		)
		(property "Description" "Ferrite Bead, 0805 [2012 Metric], 30 ohm, 8.5 A, BLM21SN, 0.004 ohm, ± 10ohm, DC power line"
			(at 276.86 59.69 0)
			(effects
				(font
					(size 1.27 1.27)
				)
				(hide yes)
			)
		)
		(property "MPN" "BLM21SN300SZ1D"
			(at 290.83 49.53 0)
			(effects
				(font
					(size 1.27 1.27)
					(thickness 0.15)
				)
				(justify left bottom)
				(hide yes)
			)
		)
		(property "Manufacturer" "Murata"
			(at 290.83 46.99 0)
			(effects
				(font
					(size 1.27 1.27)
					(thickness 0.15)
				)
				(justify left bottom)
				(hide yes)
			)
		)
		(property "License" "Apache-2.0"
			(at 290.83 41.91 0)
			(effects
				(font
					(size 1.27 1.27)
					(thickness 0.15)
				)
				(justify left bottom)
				(hide yes)
			)
		)
		(property "Author" "Antmicro"
			(at 290.83 44.45 0)
			(effects
				(font
					(size 1.27 1.27)
					(thickness 0.15)
				)
				(justify left bottom)
				(hide yes)
			)
		)
		(property "Val" "30Z/8.5A"
			(at 274.32 55.88 0)
			(effects
				(font
					(size 1.27 1.27)
				)
				(justify left bottom)
			)
		)
		(property "Current" ""
			(at 297.18 36.83 0)
			(effects
				(font
					(size 1.27 1.27)
					(thickness 0.15)
				)
				(justify left bottom)
				(hide yes)
			)
		)
		(pin "1"
		)
		(pin "2"
		)
		(instances
			(project "thunderbolt-to-10gbe-adapter"
				(path ""
					(reference "FB2")
					(unit 1)
				)
			)
		)
	)
	(symbol
		(lib_id "antmicropower:GND")
		(at 153.67 135.89 0)
		(unit 1)
		(exclude_from_sim no)
		(in_bom yes)
		(on_board yes)
		(dnp no)
		(property "Reference" "#PWR027"
			(at 153.67 142.24 0)
			(effects
				(font
					(size 1.27 1.27)
				)
				(hide yes)
			)
		)
		(property "Value" "GND"
			(at 153.67 139.7 0)
			(effects
				(font
					(size 1.27 1.27)
				)
			)
		)
		(property "Footprint" ""
			(at 153.67 135.89 0)
			(effects
				(font
					(size 1.27 1.27)
				)
				(hide yes)
			)
		)
		(property "Datasheet" ""
			(at 153.67 135.89 0)
			(effects
				(font
					(size 1.27 1.27)
				)
				(hide yes)
			)
		)
		(property "Description" ""
			(at 153.67 135.89 0)
			(effects
				(font
					(size 1.27 1.27)
				)
				(hide yes)
			)
		)
		(property "Author" "Antmicro"
			(at 162.56 143.51 0)
			(effects
				(font
					(size 1.27 1.27)
					(thickness 0.15)
				)
				(justify left bottom)
				(hide yes)
			)
		)
		(property "License" "Apache-2.0"
			(at 162.56 146.05 0)
			(effects
				(font
					(size 1.27 1.27)
					(thickness 0.15)
				)
				(justify left bottom)
				(hide yes)
			)
		)
		(pin "1"
		)
		(instances
			(project "thunderbolt-gpu-adapter"
				(path ""
					(reference "#PWR031")
					(unit 1)
				)
			)
			(project "thunderbolt-to-10gbe-adapter"
				(path ""
					(reference "#PWR027")
					(unit 1)
				)
			)
		)
	)
	(symbol
		(lib_id "antmicropower:GND")
		(at 135.89 72.39 0)
		(unit 1)
		(exclude_from_sim no)
		(in_bom yes)
		(on_board yes)
		(dnp no)
		(property "Reference" "#PWR021"
			(at 135.89 78.74 0)
			(effects
				(font
					(size 1.27 1.27)
				)
				(hide yes)
			)
		)
		(property "Value" "GND"
			(at 135.89 76.2 0)
			(effects
				(font
					(size 1.27 1.27)
				)
			)
		)
		(property "Footprint" ""
			(at 135.89 72.39 0)
			(effects
				(font
					(size 1.27 1.27)
				)
				(hide yes)
			)
		)
		(property "Datasheet" ""
			(at 135.89 72.39 0)
			(effects
				(font
					(size 1.27 1.27)
				)
				(hide yes)
			)
		)
		(property "Description" ""
			(at 135.89 72.39 0)
			(effects
				(font
					(size 1.27 1.27)
				)
				(hide yes)
			)
		)
		(property "Author" "Antmicro"
			(at 144.78 80.01 0)
			(effects
				(font
					(size 1.27 1.27)
					(thickness 0.15)
				)
				(justify left bottom)
				(hide yes)
			)
		)
		(property "License" "Apache-2.0"
			(at 144.78 82.55 0)
			(effects
				(font
					(size 1.27 1.27)
					(thickness 0.15)
				)
				(justify left bottom)
				(hide yes)
			)
		)
		(pin "1"
		)
		(instances
			(project "thunderbolt-to-10gbe-adapter"
				(path ""
					(reference "#PWR021")
					(unit 1)
				)
			)
		)
	)
	(symbol
		(lib_id "antmicroResistors0402:R_5k1_0402")
		(at 276.86 166.37 90)
		(unit 1)
		(exclude_from_sim no)
		(in_bom yes)
		(on_board yes)
		(dnp no)
		(fields_autoplaced yes)
		(property "Reference" "R33"
			(at 279.4 162.56 90)
			(effects
				(font
					(size 1.27 1.27)
					(thickness 0.15)
				)
				(justify right)
			)
		)
		(property "Value" "R_5k1_0402"
			(at 289.56 146.05 0)
			(effects
				(font
					(size 1.27 1.27)
					(thickness 0.15)
				)
				(justify left bottom)
				(hide yes)
			)
		)
		(property "Footprint" "antmicro-footprints:R_0402_1005Metric"
			(at 292.1 146.05 0)
			(effects
				(font
					(size 1.27 1.27)
					(thickness 0.15)
				)
				(justify left bottom)
				(hide yes)
			)
		)
		(property "Datasheet" "https://www.bourns.com/docs/product-datasheets/cr.pdf"
			(at 294.64 146.05 0)
			(effects
				(font
					(size 1.27 1.27)
					(thickness 0.15)
				)
				(justify left bottom)
				(hide yes)
			)
		)
		(property "Description" "SMD Chip Resistor, 5.1 kohm, ± 1%, 63 mW, 0402 [1005 Metric], Thick Film, General Purpose"
			(at 276.86 166.37 0)
			(effects
				(font
					(size 1.27 1.27)
				)
				(hide yes)
			)
		)
		(property "MPN" "CR0402-FX-5101GLF"
			(at 297.18 146.05 0)
			(effects
				(font
					(size 1.27 1.27)
					(thickness 0.15)
				)
				(justify left bottom)
				(hide yes)
			)
		)
		(property "Manufacturer" "Bourns"
			(at 299.72 146.05 0)
			(effects
				(font
					(size 1.27 1.27)
					(thickness 0.15)
				)
				(justify left bottom)
				(hide yes)
			)
		)
		(property "License" "Apache-2.0"
			(at 302.26 146.05 0)
			(effects
				(font
					(size 1.27 1.27)
					(thickness 0.15)
				)
				(justify left bottom)
				(hide yes)
			)
		)
		(property "Val" "5k1"
			(at 279.4 165.1 90)
			(effects
				(font
					(size 1.27 1.27)
					(thickness 0.15)
				)
				(justify right)
			)
		)
		(property "Tolerance" "1%"
			(at 287.02 146.05 0)
			(effects
				(font
					(size 1.27 1.27)
				)
				(justify left bottom)
				(hide yes)
			)
		)
		(property "Author" "Antmicro"
			(at 304.8 146.05 0)
			(effects
				(font
					(size 1.27 1.27)
					(thickness 0.15)
				)
				(justify left bottom)
				(hide yes)
			)
		)
		(pin "1"
		)
		(pin "2"
		)
		(instances
			(project "thunderbolt-gpu-adapter"
				(path ""
					(reference "R40")
					(unit 1)
				)
			)
			(project "thunderbolt-to-10gbe-adapter"
				(path ""
					(reference "R33")
					(unit 1)
				)
			)
		)
	)
	(symbol
		(lib_id "antmicroResistors0402:R_10k_0402")
		(at 129.54 69.85 90)
		(unit 1)
		(exclude_from_sim no)
		(in_bom yes)
		(on_board yes)
		(dnp no)
		(property "Reference" "R7"
			(at 130.81 66.04 90)
			(effects
				(font
					(size 1.27 1.27)
					(thickness 0.15)
				)
				(justify right)
			)
		)
		(property "Value" "R_10k_0402"
			(at 142.24 49.53 0)
			(effects
				(font
					(size 1.27 1.27)
					(thickness 0.15)
				)
				(justify left bottom)
				(hide yes)
			)
		)
		(property "Footprint" "antmicro-footprints:R_0402_1005Metric"
			(at 144.78 49.53 0)
			(effects
				(font
					(size 1.27 1.27)
					(thickness 0.15)
				)
				(justify left bottom)
				(hide yes)
			)
		)
		(property "Datasheet" "https://www.bourns.com/docs/product-datasheets/cr.pdf"
			(at 147.32 49.53 0)
			(effects
				(font
					(size 1.27 1.27)
					(thickness 0.15)
				)
				(justify left bottom)
				(hide yes)
			)
		)
		(property "Description" "SMD Chip Resistor, 10 kohm, ± 1%, 62.5 mW, 0402 [1005 Metric], Thick Film, General Purpose"
			(at 129.54 69.85 0)
			(effects
				(font
					(size 1.27 1.27)
				)
				(hide yes)
			)
		)
		(property "MPN" "CR0402-FX-1002GLF"
			(at 149.86 49.53 0)
			(effects
				(font
					(size 1.27 1.27)
					(thickness 0.15)
				)
				(justify left bottom)
				(hide yes)
			)
		)
		(property "Manufacturer" "Bourns"
			(at 152.4 49.53 0)
			(effects
				(font
					(size 1.27 1.27)
					(thickness 0.15)
				)
				(justify left bottom)
				(hide yes)
			)
		)
		(property "License" "Apache-2.0"
			(at 154.94 49.53 0)
			(effects
				(font
					(size 1.27 1.27)
					(thickness 0.15)
				)
				(justify left bottom)
				(hide yes)
			)
		)
		(property "Val" "10k"
			(at 130.81 68.58 90)
			(effects
				(font
					(size 1.27 1.27)
					(thickness 0.15)
				)
				(justify right)
			)
		)
		(property "Tolerance" "1%"
			(at 139.7 49.53 0)
			(effects
				(font
					(size 1.27 1.27)
				)
				(justify left bottom)
				(hide yes)
			)
		)
		(property "Author" "Antmicro"
			(at 157.48 49.53 0)
			(effects
				(font
					(size 1.27 1.27)
					(thickness 0.15)
				)
				(justify left bottom)
				(hide yes)
			)
		)
		(pin "1"
		)
		(pin "2"
		)
		(instances
			(project "thunderbolt-to-10gbe-adapter"
				(path ""
					(reference "R7")
					(unit 1)
				)
			)
		)
	)
	(symbol
		(lib_id "antmicropower:GND")
		(at 147.32 53.34 0)
		(unit 1)
		(exclude_from_sim no)
		(in_bom yes)
		(on_board yes)
		(dnp no)
		(property "Reference" "#PWR023"
			(at 147.32 59.69 0)
			(effects
				(font
					(size 1.27 1.27)
				)
				(hide yes)
			)
		)
		(property "Value" "GND"
			(at 147.32 57.15 0)
			(effects
				(font
					(size 1.27 1.27)
				)
			)
		)
		(property "Footprint" ""
			(at 147.32 53.34 0)
			(effects
				(font
					(size 1.27 1.27)
				)
				(hide yes)
			)
		)
		(property "Datasheet" ""
			(at 147.32 53.34 0)
			(effects
				(font
					(size 1.27 1.27)
				)
				(hide yes)
			)
		)
		(property "Description" ""
			(at 147.32 53.34 0)
			(effects
				(font
					(size 1.27 1.27)
				)
				(hide yes)
			)
		)
		(property "Author" "Antmicro"
			(at 156.21 60.96 0)
			(effects
				(font
					(size 1.27 1.27)
					(thickness 0.15)
				)
				(justify left bottom)
				(hide yes)
			)
		)
		(property "License" "Apache-2.0"
			(at 156.21 63.5 0)
			(effects
				(font
					(size 1.27 1.27)
					(thickness 0.15)
				)
				(justify left bottom)
				(hide yes)
			)
		)
		(pin "1"
		)
		(instances
			(project "thunderbolt-to-10gbe-adapter"
				(path ""
					(reference "#PWR023")
					(unit 1)
				)
			)
		)
	)
	(symbol
		(lib_id "antmicropower:PWR_FLAG")
		(at 115.57 41.91 0)
		(unit 1)
		(exclude_from_sim no)
		(in_bom yes)
		(on_board yes)
		(dnp no)
		(property "Reference" "#FLG04"
			(at 115.57 40.005 0)
			(effects
				(font
					(size 1.27 1.27)
				)
				(hide yes)
			)
		)
		(property "Value" "PWR_FLAG"
			(at 115.57 38.1 0)
			(effects
				(font
					(size 1.27 1.27)
				)
			)
		)
		(property "Footprint" ""
			(at 115.57 41.91 0)
			(effects
				(font
					(size 1.27 1.27)
				)
				(hide yes)
			)
		)
		(property "Datasheet" ""
			(at 115.57 41.91 0)
			(effects
				(font
					(size 1.27 1.27)
				)
				(hide yes)
			)
		)
		(property "Description" ""
			(at 115.57 44.45 0)
			(effects
				(font
					(size 1.27 1.27)
				)
				(justify left bottom)
				(hide yes)
			)
		)
		(pin "1"
		)
		(instances
			(project "thunderbolt-to-10gbe-adapter"
				(path ""
					(reference "#FLG04")
					(unit 1)
				)
			)
		)
	)
	(symbol
		(lib_id "antmicroResistors0402:R_0R_0402")
		(at 168.91 185.42 0)
		(unit 1)
		(exclude_from_sim no)
		(in_bom yes)
		(on_board yes)
		(dnp no)
		(fields_autoplaced yes)
		(property "Reference" "R16"
			(at 171.45 183.515 0)
			(effects
				(font
					(size 1.27 1.27)
					(thickness 0.15)
				)
			)
		)
		(property "Value" "R_0R_0402"
			(at 189.23 198.12 0)
			(effects
				(font
					(size 1.27 1.27)
					(thickness 0.15)
				)
				(justify left bottom)
				(hide yes)
			)
		)
		(property "Footprint" "antmicro-footprints:R_0402_1005Metric"
			(at 189.23 200.66 0)
			(effects
				(font
					(size 1.27 1.27)
					(thickness 0.15)
				)
				(justify left bottom)
				(hide yes)
			)
		)
		(property "Datasheet" "https://industrial.panasonic.com/cdbs/www-data/pdf/RDA0000/AOA0000C301.pdf"
			(at 189.23 203.2 0)
			(effects
				(font
					(size 1.27 1.27)
					(thickness 0.15)
				)
				(justify left bottom)
				(hide yes)
			)
		)
		(property "Description" "SMD Chip Resistor, Jumper, 0 ohm, 100 mW, 0402 [1005 Metric], Thick Film, General Purpose"
			(at 168.91 185.42 0)
			(effects
				(font
					(size 1.27 1.27)
				)
				(hide yes)
			)
		)
		(property "MPN" "ERJ2GE0R00X"
			(at 189.23 205.74 0)
			(effects
				(font
					(size 1.27 1.27)
					(thickness 0.15)
				)
				(justify left bottom)
				(hide yes)
			)
		)
		(property "Manufacturer" "Panasonic"
			(at 189.23 208.28 0)
			(effects
				(font
					(size 1.27 1.27)
					(thickness 0.15)
				)
				(justify left bottom)
				(hide yes)
			)
		)
		(property "License" "Apache-2.0"
			(at 189.23 210.82 0)
			(effects
				(font
					(size 1.27 1.27)
					(thickness 0.15)
				)
				(justify left bottom)
				(hide yes)
			)
		)
		(property "Val" "0R"
			(at 171.45 185.42 0)
			(effects
				(font
					(size 1.27 1.27)
					(thickness 0.15)
				)
			)
		)
		(property "Tolerance" "~"
			(at 189.23 195.58 0)
			(effects
				(font
					(size 1.27 1.27)
				)
				(justify left bottom)
				(hide yes)
			)
		)
		(property "Current" "1A"
			(at 171.45 181.61 0)
			(effects
				(font
					(size 1.27 1.27)
					(thickness 0.15)
				)
				(hide yes)
			)
		)
		(property "Author" "Antmicro"
			(at 189.23 213.36 0)
			(effects
				(font
					(size 1.27 1.27)
					(thickness 0.15)
				)
				(justify left bottom)
				(hide yes)
			)
		)
		(pin "1"
		)
		(pin "2"
		)
		(instances
			(project "thunderbolt-gpu-adapter"
				(path ""
					(reference "R18")
					(unit 1)
				)
			)
			(project "thunderbolt-to-10gbe-adapter"
				(path ""
					(reference "R16")
					(unit 1)
				)
			)
		)
	)
	(symbol
		(lib_id "antmicroResistors0402:R_5k1_0402")
		(at 259.08 166.37 270)
		(mirror x)
		(unit 1)
		(exclude_from_sim no)
		(in_bom yes)
		(on_board yes)
		(dnp no)
		(property "Reference" "R30"
			(at 256.54 162.56 90)
			(effects
				(font
					(size 1.27 1.27)
					(thickness 0.15)
				)
				(justify right)
			)
		)
		(property "Value" "R_5k1_0402"
			(at 246.38 146.05 0)
			(effects
				(font
					(size 1.27 1.27)
					(thickness 0.15)
				)
				(justify left bottom)
				(hide yes)
			)
		)
		(property "Footprint" "antmicro-footprints:R_0402_1005Metric"
			(at 243.84 146.05 0)
			(effects
				(font
					(size 1.27 1.27)
					(thickness 0.15)
				)
				(justify left bottom)
				(hide yes)
			)
		)
		(property "Datasheet" "https://www.bourns.com/docs/product-datasheets/cr.pdf"
			(at 241.3 146.05 0)
			(effects
				(font
					(size 1.27 1.27)
					(thickness 0.15)
				)
				(justify left bottom)
				(hide yes)
			)
		)
		(property "Description" "SMD Chip Resistor, 5.1 kohm, ± 1%, 63 mW, 0402 [1005 Metric], Thick Film, General Purpose"
			(at 259.08 166.37 0)
			(effects
				(font
					(size 1.27 1.27)
				)
				(hide yes)
			)
		)
		(property "MPN" "CR0402-FX-5101GLF"
			(at 238.76 146.05 0)
			(effects
				(font
					(size 1.27 1.27)
					(thickness 0.15)
				)
				(justify left bottom)
				(hide yes)
			)
		)
		(property "Manufacturer" "Bourns"
			(at 236.22 146.05 0)
			(effects
				(font
					(size 1.27 1.27)
					(thickness 0.15)
				)
				(justify left bottom)
				(hide yes)
			)
		)
		(property "License" "Apache-2.0"
			(at 233.68 146.05 0)
			(effects
				(font
					(size 1.27 1.27)
					(thickness 0.15)
				)
				(justify left bottom)
				(hide yes)
			)
		)
		(property "Val" "5k1"
			(at 256.54 165.1 90)
			(effects
				(font
					(size 1.27 1.27)
					(thickness 0.15)
				)
				(justify right)
			)
		)
		(property "Tolerance" "1%"
			(at 248.92 146.05 0)
			(effects
				(font
					(size 1.27 1.27)
				)
				(justify left bottom)
				(hide yes)
			)
		)
		(property "Author" "Antmicro"
			(at 231.14 146.05 0)
			(effects
				(font
					(size 1.27 1.27)
					(thickness 0.15)
				)
				(justify left bottom)
				(hide yes)
			)
		)
		(pin "1"
		)
		(pin "2"
		)
		(instances
			(project "thunderbolt-gpu-adapter"
				(path ""
					(reference "R38")
					(unit 1)
				)
			)
			(project "thunderbolt-to-10gbe-adapter"
				(path ""
					(reference "R30")
					(unit 1)
				)
			)
		)
	)
	(symbol
		(lib_id "antmicroResistors0402:R_10k_0402")
		(at 168.91 175.26 0)
		(unit 1)
		(exclude_from_sim no)
		(in_bom yes)
		(on_board yes)
		(dnp no)
		(fields_autoplaced yes)
		(property "Reference" "R15"
			(at 171.45 173.355 0)
			(effects
				(font
					(size 1.27 1.27)
					(thickness 0.15)
				)
			)
		)
		(property "Value" "R_10k_0402"
			(at 189.23 187.96 0)
			(effects
				(font
					(size 1.27 1.27)
					(thickness 0.15)
				)
				(justify left bottom)
				(hide yes)
			)
		)
		(property "Footprint" "antmicro-footprints:R_0402_1005Metric"
			(at 189.23 190.5 0)
			(effects
				(font
					(size 1.27 1.27)
					(thickness 0.15)
				)
				(justify left bottom)
				(hide yes)
			)
		)
		(property "Datasheet" "https://www.bourns.com/docs/product-datasheets/cr.pdf"
			(at 189.23 193.04 0)
			(effects
				(font
					(size 1.27 1.27)
					(thickness 0.15)
				)
				(justify left bottom)
				(hide yes)
			)
		)
		(property "Description" "SMD Chip Resistor, 10 kohm, ± 1%, 62.5 mW, 0402 [1005 Metric], Thick Film, General Purpose"
			(at 168.91 175.26 0)
			(effects
				(font
					(size 1.27 1.27)
				)
				(hide yes)
			)
		)
		(property "MPN" "CR0402-FX-1002GLF"
			(at 189.23 195.58 0)
			(effects
				(font
					(size 1.27 1.27)
					(thickness 0.15)
				)
				(justify left bottom)
				(hide yes)
			)
		)
		(property "Manufacturer" "Bourns"
			(at 189.23 198.12 0)
			(effects
				(font
					(size 1.27 1.27)
					(thickness 0.15)
				)
				(justify left bottom)
				(hide yes)
			)
		)
		(property "License" "Apache-2.0"
			(at 189.23 200.66 0)
			(effects
				(font
					(size 1.27 1.27)
					(thickness 0.15)
				)
				(justify left bottom)
				(hide yes)
			)
		)
		(property "Val" "10k"
			(at 171.45 177.165 0)
			(effects
				(font
					(size 1.27 1.27)
					(thickness 0.15)
				)
			)
		)
		(property "Tolerance" "1%"
			(at 189.23 185.42 0)
			(effects
				(font
					(size 1.27 1.27)
				)
				(justify left bottom)
				(hide yes)
			)
		)
		(property "Author" "Antmicro"
			(at 189.23 203.2 0)
			(effects
				(font
					(size 1.27 1.27)
					(thickness 0.15)
				)
				(justify left bottom)
				(hide yes)
			)
		)
		(pin "1"
		)
		(pin "2"
		)
		(instances
			(project "thunderbolt-gpu-adapter"
				(path ""
					(reference "R17")
					(unit 1)
				)
			)
			(project "thunderbolt-to-10gbe-adapter"
				(path ""
					(reference "R15")
					(unit 1)
				)
			)
		)
	)
	(symbol
		(lib_id "antmicroResistors0402:R_10k_0402")
		(at 125.73 62.23 180)
		(unit 1)
		(exclude_from_sim no)
		(in_bom yes)
		(on_board yes)
		(dnp no)
		(property "Reference" "R6"
			(at 123.19 59.69 0)
			(effects
				(font
					(size 1.27 1.27)
					(thickness 0.15)
				)
			)
		)
		(property "Value" "R_10k_0402"
			(at 105.41 49.53 0)
			(effects
				(font
					(size 1.27 1.27)
					(thickness 0.15)
				)
				(justify left bottom)
				(hide yes)
			)
		)
		(property "Footprint" "antmicro-footprints:R_0402_1005Metric"
			(at 105.41 46.99 0)
			(effects
				(font
					(size 1.27 1.27)
					(thickness 0.15)
				)
				(justify left bottom)
				(hide yes)
			)
		)
		(property "Datasheet" "https://www.bourns.com/docs/product-datasheets/cr.pdf"
			(at 105.41 44.45 0)
			(effects
				(font
					(size 1.27 1.27)
					(thickness 0.15)
				)
				(justify left bottom)
				(hide yes)
			)
		)
		(property "Description" "SMD Chip Resistor, 10 kohm, ± 1%, 62.5 mW, 0402 [1005 Metric], Thick Film, General Purpose"
			(at 125.73 62.23 0)
			(effects
				(font
					(size 1.27 1.27)
				)
				(hide yes)
			)
		)
		(property "MPN" "CR0402-FX-1002GLF"
			(at 105.41 41.91 0)
			(effects
				(font
					(size 1.27 1.27)
					(thickness 0.15)
				)
				(justify left bottom)
				(hide yes)
			)
		)
		(property "Manufacturer" "Bourns"
			(at 105.41 39.37 0)
			(effects
				(font
					(size 1.27 1.27)
					(thickness 0.15)
				)
				(justify left bottom)
				(hide yes)
			)
		)
		(property "License" "Apache-2.0"
			(at 105.41 36.83 0)
			(effects
				(font
					(size 1.27 1.27)
					(thickness 0.15)
				)
				(justify left bottom)
				(hide yes)
			)
		)
		(property "Val" "10k"
			(at 123.19 64.77 0)
			(effects
				(font
					(size 1.27 1.27)
					(thickness 0.15)
				)
			)
		)
		(property "Tolerance" "1%"
			(at 105.41 52.07 0)
			(effects
				(font
					(size 1.27 1.27)
				)
				(justify left bottom)
				(hide yes)
			)
		)
		(property "Author" "Antmicro"
			(at 105.41 34.29 0)
			(effects
				(font
					(size 1.27 1.27)
					(thickness 0.15)
				)
				(justify left bottom)
				(hide yes)
			)
		)
		(pin "1"
		)
		(pin "2"
		)
		(instances
			(project "thunderbolt-to-10gbe-adapter"
				(path ""
					(reference "R6")
					(unit 1)
				)
			)
		)
	)
	(symbol
		(lib_id "antmicropower:GND")
		(at 148.59 76.2 0)
		(unit 1)
		(exclude_from_sim no)
		(in_bom yes)
		(on_board yes)
		(dnp no)
		(property "Reference" "#PWR025"
			(at 148.59 82.55 0)
			(effects
				(font
					(size 1.27 1.27)
				)
				(hide yes)
			)
		)
		(property "Value" "GND"
			(at 148.59 80.01 0)
			(effects
				(font
					(size 1.27 1.27)
				)
			)
		)
		(property "Footprint" ""
			(at 148.59 76.2 0)
			(effects
				(font
					(size 1.27 1.27)
				)
				(hide yes)
			)
		)
		(property "Datasheet" ""
			(at 148.59 76.2 0)
			(effects
				(font
					(size 1.27 1.27)
				)
				(hide yes)
			)
		)
		(property "Description" ""
			(at 148.59 76.2 0)
			(effects
				(font
					(size 1.27 1.27)
				)
				(hide yes)
			)
		)
		(property "Author" "Antmicro"
			(at 157.48 83.82 0)
			(effects
				(font
					(size 1.27 1.27)
					(thickness 0.15)
				)
				(justify left bottom)
				(hide yes)
			)
		)
		(property "License" "Apache-2.0"
			(at 157.48 86.36 0)
			(effects
				(font
					(size 1.27 1.27)
					(thickness 0.15)
				)
				(justify left bottom)
				(hide yes)
			)
		)
		(pin "1"
		)
		(instances
			(project "thunderbolt-to-10gbe-adapter"
				(path ""
					(reference "#PWR025")
					(unit 1)
				)
			)
		)
	)
	(symbol
		(lib_id "antmicroCapacitors0402:C_1u_0402")
		(at 148.59 73.66 90)
		(unit 1)
		(exclude_from_sim no)
		(in_bom yes)
		(on_board yes)
		(dnp no)
		(property "Reference" "C11"
			(at 149.225 69.215 90)
			(effects
				(font
					(size 1.27 1.27)
					(thickness 0.15)
				)
				(justify right)
			)
		)
		(property "Value" "C_1u_0402"
			(at 158.75 53.34 0)
			(effects
				(font
					(size 1.27 1.27)
					(thickness 0.15)
				)
				(justify left bottom)
				(hide yes)
			)
		)
		(property "Footprint" "antmicro-footprints:C_0402_1005Metric"
			(at 161.29 53.34 0)
			(effects
				(font
					(size 1.27 1.27)
					(thickness 0.15)
				)
				(justify left bottom)
				(hide yes)
			)
		)
		(property "Datasheet" "https://product.tdk.com/en/search/capacitor/ceramic/mlcc/info?part_no=C1005X6S1A105K050BC"
			(at 163.83 53.34 0)
			(effects
				(font
					(size 1.27 1.27)
					(thickness 0.15)
				)
				(justify left bottom)
				(hide yes)
			)
		)
		(property "Description" "SMD Multilayer Ceramic Capacitor, 1 µF, 10 V, 0402 [1005 Metric], ± 10%, X6S, C"
			(at 148.59 73.66 0)
			(effects
				(font
					(size 1.27 1.27)
				)
				(hide yes)
			)
		)
		(property "MPN" "C1005X6S1A105K050BC"
			(at 166.37 53.34 0)
			(effects
				(font
					(size 1.27 1.27)
					(thickness 0.15)
				)
				(justify left bottom)
				(hide yes)
			)
		)
		(property "Manufacturer" "TDK"
			(at 168.91 53.34 0)
			(effects
				(font
					(size 1.27 1.27)
					(thickness 0.15)
				)
				(justify left bottom)
				(hide yes)
			)
		)
		(property "License" "Apache-2.0"
			(at 171.45 53.34 0)
			(effects
				(font
					(size 1.27 1.27)
					(thickness 0.15)
				)
				(justify left bottom)
				(hide yes)
			)
		)
		(property "Val" "1u"
			(at 149.225 73.025 90)
			(effects
				(font
					(size 1.27 1.27)
					(thickness 0.15)
				)
				(justify right)
			)
		)
		(property "Voltage" ""
			(at 176.53 53.34 0)
			(effects
				(font
					(size 1.27 1.27)
				)
				(justify left bottom)
				(hide yes)
			)
		)
		(property "Dielectric" ""
			(at 179.07 53.34 0)
			(effects
				(font
					(size 1.27 1.27)
				)
				(justify left bottom)
				(hide yes)
			)
		)
		(property "Author" "Antmicro"
			(at 173.99 53.34 0)
			(effects
				(font
					(size 1.27 1.27)
					(thickness 0.15)
				)
				(justify left bottom)
				(hide yes)
			)
		)
		(pin "1"
		)
		(pin "2"
		)
		(instances
			(project "thunderbolt-to-10gbe-adapter"
				(path ""
					(reference "C11")
					(unit 1)
				)
			)
		)
	)
	(symbol
		(lib_id "antmicroCapacitors0402:C_220p_0402")
		(at 266.7 166.37 90)
		(unit 1)
		(exclude_from_sim no)
		(in_bom yes)
		(on_board yes)
		(dnp no)
		(fields_autoplaced yes)
		(property "Reference" "C29"
			(at 269.24 162.5536 90)
			(effects
				(font
					(size 1.27 1.27)
					(thickness 0.15)
				)
				(justify right)
			)
		)
		(property "Value" "C_220p_0402"
			(at 276.86 146.05 0)
			(effects
				(font
					(size 1.27 1.27)
					(thickness 0.15)
				)
				(justify left bottom)
				(hide yes)
			)
		)
		(property "Footprint" "antmicro-footprints:C_0402_1005Metric"
			(at 279.4 146.05 0)
			(effects
				(font
					(size 1.27 1.27)
					(thickness 0.15)
				)
				(justify left bottom)
				(hide yes)
			)
		)
		(property "Datasheet" "https://spicat.kyocera-avx.com/product/mlcc/chartview/04025C221JAT2A/"
			(at 281.94 146.05 0)
			(effects
				(font
					(size 1.27 1.27)
					(thickness 0.15)
				)
				(justify left bottom)
				(hide yes)
			)
		)
		(property "Description" "SMD Multilayer Ceramic Capacitor, 220 pF, 50 V, 0402 [1005 Metric], ± 10%, X7R, MC"
			(at 266.7 166.37 0)
			(effects
				(font
					(size 1.27 1.27)
				)
				(hide yes)
			)
		)
		(property "MPN" "04025C221JAT2A"
			(at 284.48 146.05 0)
			(effects
				(font
					(size 1.27 1.27)
					(thickness 0.15)
				)
				(justify left bottom)
				(hide yes)
			)
		)
		(property "Manufacturer" "KYOCERA AVX"
			(at 287.02 146.05 0)
			(effects
				(font
					(size 1.27 1.27)
					(thickness 0.15)
				)
				(justify left bottom)
				(hide yes)
			)
		)
		(property "License" "Apache-2.0"
			(at 289.56 146.05 0)
			(effects
				(font
					(size 1.27 1.27)
					(thickness 0.15)
				)
				(justify left bottom)
				(hide yes)
			)
		)
		(property "Val" "220p"
			(at 269.24 165.0936 90)
			(effects
				(font
					(size 1.27 1.27)
					(thickness 0.15)
				)
				(justify right)
			)
		)
		(property "Voltage" ""
			(at 294.64 146.05 0)
			(effects
				(font
					(size 1.27 1.27)
				)
				(justify left bottom)
				(hide yes)
			)
		)
		(property "Dielectric" ""
			(at 297.18 146.05 0)
			(effects
				(font
					(size 1.27 1.27)
				)
				(justify left bottom)
				(hide yes)
			)
		)
		(property "Author" "Antmicro"
			(at 292.1 146.05 0)
			(effects
				(font
					(size 1.27 1.27)
					(thickness 0.15)
				)
				(justify left bottom)
				(hide yes)
			)
		)
		(pin "1"
		)
		(pin "2"
		)
		(instances
			(project "thunderbolt-gpu-adapter"
				(path ""
					(reference "C45")
					(unit 1)
				)
			)
			(project "thunderbolt-to-10gbe-adapter"
				(path ""
					(reference "C29")
					(unit 1)
				)
			)
		)
	)
	(symbol
		(lib_id "antmicroResistors0402:R_100k_0402")
		(at 240.03 236.22 0)
		(unit 1)
		(exclude_from_sim no)
		(in_bom yes)
		(on_board yes)
		(dnp no)
		(property "Reference" "R28"
			(at 238.125 234.95 0)
			(effects
				(font
					(size 1.27 1.27)
					(thickness 0.15)
				)
			)
		)
		(property "Value" "R_100k_0402"
			(at 260.35 248.92 0)
			(effects
				(font
					(size 1.27 1.27)
					(thickness 0.15)
				)
				(justify left bottom)
				(hide yes)
			)
		)
		(property "Footprint" "antmicro-footprints:R_0402_1005Metric"
			(at 260.35 251.46 0)
			(effects
				(font
					(size 1.27 1.27)
					(thickness 0.15)
				)
				(justify left bottom)
				(hide yes)
			)
		)
		(property "Datasheet" "https://www.bourns.com/docs/product-datasheets/cr.pdf"
			(at 260.35 254 0)
			(effects
				(font
					(size 1.27 1.27)
					(thickness 0.15)
				)
				(justify left bottom)
				(hide yes)
			)
		)
		(property "Description" "SMD Chip Resistor, 100 kohm, ± 1%, 62.5 mW, 0402 [1005 Metric], Thick Film, General Purpose"
			(at 240.03 236.22 0)
			(effects
				(font
					(size 1.27 1.27)
				)
				(hide yes)
			)
		)
		(property "MPN" "CR0402-FX-1003GLF"
			(at 260.35 256.54 0)
			(effects
				(font
					(size 1.27 1.27)
					(thickness 0.15)
				)
				(justify left bottom)
				(hide yes)
			)
		)
		(property "Manufacturer" "Bourns"
			(at 260.35 259.08 0)
			(effects
				(font
					(size 1.27 1.27)
					(thickness 0.15)
				)
				(justify left bottom)
				(hide yes)
			)
		)
		(property "License" "Apache-2.0"
			(at 260.35 261.62 0)
			(effects
				(font
					(size 1.27 1.27)
					(thickness 0.15)
				)
				(justify left bottom)
				(hide yes)
			)
		)
		(property "Val" "100k"
			(at 247.015 234.95 0)
			(effects
				(font
					(size 1.27 1.27)
					(thickness 0.15)
				)
			)
		)
		(property "Tolerance" "1%"
			(at 260.35 246.38 0)
			(effects
				(font
					(size 1.27 1.27)
				)
				(justify left bottom)
				(hide yes)
			)
		)
		(property "Author" "Antmicro"
			(at 260.35 264.16 0)
			(effects
				(font
					(size 1.27 1.27)
					(thickness 0.15)
				)
				(justify left bottom)
				(hide yes)
			)
		)
		(pin "1"
		)
		(pin "2"
		)
		(instances
			(project "thunderbolt-gpu-adapter"
				(path ""
					(reference "R34")
					(unit 1)
				)
			)
			(project "thunderbolt-to-10gbe-adapter"
				(path ""
					(reference "R28")
					(unit 1)
				)
			)
		)
	)
	(symbol
		(lib_id "antmicroCapacitors0402:C_2u2_0402")
		(at 237.49 142.24 0)
		(unit 1)
		(exclude_from_sim no)
		(in_bom yes)
		(on_board yes)
		(dnp no)
		(property "Reference" "C20"
			(at 242.57 140.97 0)
			(effects
				(font
					(size 1.27 1.27)
					(thickness 0.15)
				)
			)
		)
		(property "Value" "C_2u2_0402"
			(at 257.81 152.4 0)
			(effects
				(font
					(size 1.27 1.27)
					(thickness 0.15)
				)
				(justify left bottom)
				(hide yes)
			)
		)
		(property "Footprint" "antmicro-footprints:C_0402_1005Metric"
			(at 257.81 154.94 0)
			(effects
				(font
					(size 1.27 1.27)
					(thickness 0.15)
				)
				(justify left bottom)
				(hide yes)
			)
		)
		(property "Datasheet" "https://product.tdk.com/en/search/capacitor/ceramic/mlcc/info?part_no=C1005X5R1A225K050BC"
			(at 257.81 157.48 0)
			(effects
				(font
					(size 1.27 1.27)
					(thickness 0.15)
				)
				(justify left bottom)
				(hide yes)
			)
		)
		(property "Description" "SMD Multilayer Ceramic Capacitor, 2.2 µF, 10 V, 0402 [1005 Metric], ± 10%, X5R, C"
			(at 237.49 142.24 0)
			(effects
				(font
					(size 1.27 1.27)
				)
				(hide yes)
			)
		)
		(property "MPN" "C1005X5R1A225K050BC"
			(at 257.81 160.02 0)
			(effects
				(font
					(size 1.27 1.27)
					(thickness 0.15)
				)
				(justify left bottom)
				(hide yes)
			)
		)
		(property "Manufacturer" "TDK"
			(at 257.81 162.56 0)
			(effects
				(font
					(size 1.27 1.27)
					(thickness 0.15)
				)
				(justify left bottom)
				(hide yes)
			)
		)
		(property "License" "Apache-2.0"
			(at 257.81 165.1 0)
			(effects
				(font
					(size 1.27 1.27)
					(thickness 0.15)
				)
				(justify left bottom)
				(hide yes)
			)
		)
		(property "Val" "2u2"
			(at 242.57 143.51 0)
			(effects
				(font
					(size 1.27 1.27)
					(thickness 0.15)
				)
			)
		)
		(property "Voltage" ""
			(at 257.81 170.18 0)
			(effects
				(font
					(size 1.27 1.27)
				)
				(justify left bottom)
				(hide yes)
			)
		)
		(property "Dielectric" ""
			(at 257.81 172.72 0)
			(effects
				(font
					(size 1.27 1.27)
				)
				(justify left bottom)
				(hide yes)
			)
		)
		(property "Author" "Antmicro"
			(at 257.81 167.64 0)
			(effects
				(font
					(size 1.27 1.27)
					(thickness 0.15)
				)
				(justify left bottom)
				(hide yes)
			)
		)
		(pin "1"
		)
		(pin "2"
		)
		(instances
			(project "thunderbolt-gpu-adapter"
				(path ""
					(reference "C35")
					(unit 1)
				)
			)
			(project "thunderbolt-to-10gbe-adapter"
				(path ""
					(reference "C20")
					(unit 1)
				)
			)
		)
	)
	(symbol
		(lib_id "antmicropower:GND")
		(at 129.54 53.34 0)
		(unit 1)
		(exclude_from_sim no)
		(in_bom yes)
		(on_board yes)
		(dnp no)
		(property "Reference" "#PWR018"
			(at 129.54 59.69 0)
			(effects
				(font
					(size 1.27 1.27)
				)
				(hide yes)
			)
		)
		(property "Value" "GND"
			(at 129.54 57.15 0)
			(effects
				(font
					(size 1.27 1.27)
				)
			)
		)
		(property "Footprint" ""
			(at 129.54 53.34 0)
			(effects
				(font
					(size 1.27 1.27)
				)
				(hide yes)
			)
		)
		(property "Datasheet" ""
			(at 129.54 53.34 0)
			(effects
				(font
					(size 1.27 1.27)
				)
				(hide yes)
			)
		)
		(property "Description" ""
			(at 129.54 53.34 0)
			(effects
				(font
					(size 1.27 1.27)
				)
				(hide yes)
			)
		)
		(property "Author" "Antmicro"
			(at 138.43 60.96 0)
			(effects
				(font
					(size 1.27 1.27)
					(thickness 0.15)
				)
				(justify left bottom)
				(hide yes)
			)
		)
		(property "License" "Apache-2.0"
			(at 138.43 63.5 0)
			(effects
				(font
					(size 1.27 1.27)
					(thickness 0.15)
				)
				(justify left bottom)
				(hide yes)
			)
		)
		(pin "1"
		)
		(instances
			(project "thunderbolt-to-10gbe-adapter"
				(path ""
					(reference "#PWR018")
					(unit 1)
				)
			)
		)
	)
	(symbol
		(lib_id "antmicropower:PWR_FLAG")
		(at 170.18 128.27 0)
		(unit 1)
		(exclude_from_sim no)
		(in_bom yes)
		(on_board yes)
		(dnp no)
		(property "Reference" "#FLG05"
			(at 170.18 126.365 0)
			(effects
				(font
					(size 1.27 1.27)
				)
				(hide yes)
			)
		)
		(property "Value" "PWR_FLAG"
			(at 170.18 124.46 0)
			(effects
				(font
					(size 1.27 1.27)
				)
				(hide yes)
			)
		)
		(property "Footprint" ""
			(at 170.18 128.27 0)
			(effects
				(font
					(size 1.27 1.27)
				)
				(hide yes)
			)
		)
		(property "Datasheet" ""
			(at 170.18 128.27 0)
			(effects
				(font
					(size 1.27 1.27)
				)
				(hide yes)
			)
		)
		(property "Description" ""
			(at 170.18 130.81 0)
			(effects
				(font
					(size 1.27 1.27)
				)
				(justify left bottom)
				(hide yes)
			)
		)
		(pin "1"
		)
		(instances
			(project "thunderbolt-to-10gbe-adapter"
				(path ""
					(reference "#FLG05")
					(unit 1)
				)
			)
		)
	)
	(symbol
		(lib_id "antmicropower:GND")
		(at 119.38 53.34 0)
		(unit 1)
		(exclude_from_sim no)
		(in_bom yes)
		(on_board yes)
		(dnp no)
		(property "Reference" "#PWR017"
			(at 119.38 59.69 0)
			(effects
				(font
					(size 1.27 1.27)
				)
				(hide yes)
			)
		)
		(property "Value" "GND"
			(at 119.38 57.15 0)
			(effects
				(font
					(size 1.27 1.27)
				)
			)
		)
		(property "Footprint" ""
			(at 119.38 53.34 0)
			(effects
				(font
					(size 1.27 1.27)
				)
				(hide yes)
			)
		)
		(property "Datasheet" ""
			(at 119.38 53.34 0)
			(effects
				(font
					(size 1.27 1.27)
				)
				(hide yes)
			)
		)
		(property "Description" ""
			(at 119.38 53.34 0)
			(effects
				(font
					(size 1.27 1.27)
				)
				(hide yes)
			)
		)
		(property "Author" "Antmicro"
			(at 128.27 60.96 0)
			(effects
				(font
					(size 1.27 1.27)
					(thickness 0.15)
				)
				(justify left bottom)
				(hide yes)
			)
		)
		(property "License" "Apache-2.0"
			(at 128.27 63.5 0)
			(effects
				(font
					(size 1.27 1.27)
					(thickness 0.15)
				)
				(justify left bottom)
				(hide yes)
			)
		)
		(pin "1"
		)
		(instances
			(project "thunderbolt-to-10gbe-adapter"
				(path ""
					(reference "#PWR017")
					(unit 1)
				)
			)
		)
	)
	(symbol
		(lib_id "antmicroResistors0402:R_3k3_0402")
		(at 168.91 165.1 0)
		(unit 1)
		(exclude_from_sim no)
		(in_bom yes)
		(on_board yes)
		(dnp no)
		(property "Reference" "R12"
			(at 167.64 163.83 0)
			(effects
				(font
					(size 1.27 1.27)
					(thickness 0.15)
				)
			)
		)
		(property "Value" "R_3k3_0402"
			(at 189.23 177.8 0)
			(effects
				(font
					(size 1.27 1.27)
					(thickness 0.15)
				)
				(justify left bottom)
				(hide yes)
			)
		)
		(property "Footprint" "antmicro-footprints:R_0402_1005Metric"
			(at 189.23 180.34 0)
			(effects
				(font
					(size 1.27 1.27)
					(thickness 0.15)
				)
				(justify left bottom)
				(hide yes)
			)
		)
		(property "Datasheet" "https://www.bourns.com/docs/product-datasheets/cr.pdf"
			(at 189.23 182.88 0)
			(effects
				(font
					(size 1.27 1.27)
					(thickness 0.15)
				)
				(justify left bottom)
				(hide yes)
			)
		)
		(property "Description" "SMD Chip Resistor, 3.3 kohm, ± 1%, 63 mW, 0402 [1005 Metric], Thick Film, General Purpose"
			(at 168.91 165.1 0)
			(effects
				(font
					(size 1.27 1.27)
				)
				(hide yes)
			)
		)
		(property "MPN" "CR0402-FX-3301GLF"
			(at 189.23 185.42 0)
			(effects
				(font
					(size 1.27 1.27)
					(thickness 0.15)
				)
				(justify left bottom)
				(hide yes)
			)
		)
		(property "Manufacturer" "Bourns"
			(at 189.23 187.96 0)
			(effects
				(font
					(size 1.27 1.27)
					(thickness 0.15)
				)
				(justify left bottom)
				(hide yes)
			)
		)
		(property "License" "Apache-2.0"
			(at 189.23 190.5 0)
			(effects
				(font
					(size 1.27 1.27)
					(thickness 0.15)
				)
				(justify left bottom)
				(hide yes)
			)
		)
		(property "Val" "3k3"
			(at 175.26 163.83 0)
			(effects
				(font
					(size 1.27 1.27)
					(thickness 0.15)
				)
			)
		)
		(property "Tolerance" "1%"
			(at 189.23 175.26 0)
			(effects
				(font
					(size 1.27 1.27)
				)
				(justify left bottom)
				(hide yes)
			)
		)
		(property "Author" "Antmicro"
			(at 189.23 193.04 0)
			(effects
				(font
					(size 1.27 1.27)
					(thickness 0.15)
				)
				(justify left bottom)
				(hide yes)
			)
		)
		(pin "1"
		)
		(pin "2"
		)
		(instances
			(project "thunderbolt-gpu-adapter"
				(path ""
					(reference "R14")
					(unit 1)
				)
			)
			(project "thunderbolt-to-10gbe-adapter"
				(path ""
					(reference "R12")
					(unit 1)
				)
			)
		)
	)
	(symbol
		(lib_id "antmicropower:GND")
		(at 248.92 77.47 0)
		(unit 1)
		(exclude_from_sim no)
		(in_bom yes)
		(on_board yes)
		(dnp no)
		(fields_autoplaced yes)
		(property "Reference" "#PWR036"
			(at 248.92 83.82 0)
			(effects
				(font
					(size 1.27 1.27)
				)
				(hide yes)
			)
		)
		(property "Value" "GND"
			(at 248.92 81.28 0)
			(effects
				(font
					(size 1.27 1.27)
				)
			)
		)
		(property "Footprint" ""
			(at 248.92 77.47 0)
			(effects
				(font
					(size 1.27 1.27)
				)
				(hide yes)
			)
		)
		(property "Datasheet" ""
			(at 248.92 77.47 0)
			(effects
				(font
					(size 1.27 1.27)
				)
				(hide yes)
			)
		)
		(property "Description" ""
			(at 248.92 77.47 0)
			(effects
				(font
					(size 1.27 1.27)
				)
				(hide yes)
			)
		)
		(property "Author" "Antmicro"
			(at 257.81 85.09 0)
			(effects
				(font
					(size 1.27 1.27)
					(thickness 0.15)
				)
				(justify left bottom)
				(hide yes)
			)
		)
		(property "License" "Apache-2.0"
			(at 257.81 87.63 0)
			(effects
				(font
					(size 1.27 1.27)
					(thickness 0.15)
				)
				(justify left bottom)
				(hide yes)
			)
		)
		(pin "1"
		)
		(instances
			(project "thunderbolt-to-10gbe-adapter"
				(path ""
					(reference "#PWR036")
					(unit 1)
				)
			)
		)
	)
	(symbol
		(lib_id "antmicropower:+5V")
		(at 83.82 40.64 0)
		(unit 1)
		(exclude_from_sim no)
		(in_bom yes)
		(on_board yes)
		(dnp no)
		(property "Reference" "#PWR015"
			(at 99.06 43.18 0)
			(effects
				(font
					(size 1.27 1.27)
					(thickness 0.15)
				)
				(justify left bottom)
				(hide yes)
			)
		)
		(property "Value" "+5V_USB"
			(at 83.82 36.83 0)
			(effects
				(font
					(size 1.27 1.27)
					(thickness 0.15)
				)
			)
		)
		(property "Footprint" ""
			(at 99.06 48.26 0)
			(effects
				(font
					(size 1.27 1.27)
					(thickness 0.15)
				)
				(justify left bottom)
				(hide yes)
			)
		)
		(property "Datasheet" ""
			(at 99.06 50.8 0)
			(effects
				(font
					(size 1.27 1.27)
					(thickness 0.15)
				)
				(justify left bottom)
				(hide yes)
			)
		)
		(property "Description" ""
			(at 99.06 53.34 0)
			(effects
				(font
					(size 1.27 1.27)
				)
				(justify left bottom)
				(hide yes)
			)
		)
		(property "Author" "Antmicro"
			(at 99.06 48.26 0)
			(effects
				(font
					(size 1.27 1.27)
					(thickness 0.15)
				)
				(justify left bottom)
				(hide yes)
			)
		)
		(property "License" "Apache-2.0"
			(at 99.06 50.8 0)
			(effects
				(font
					(size 1.27 1.27)
					(thickness 0.15)
				)
				(justify left bottom)
				(hide yes)
			)
		)
		(pin "1"
		)
		(instances
			(project "thunderbolt-to-10gbe-adapter"
				(path ""
					(reference "#PWR015")
					(unit 1)
				)
			)
		)
	)
	(symbol
		(lib_id "antmicroCapacitors0402:C_220n_0402")
		(at 237.49 254 90)
		(unit 1)
		(exclude_from_sim no)
		(in_bom yes)
		(on_board yes)
		(dnp no)
		(fields_autoplaced yes)
		(property "Reference" "C23"
			(at 240.665 250.1835 90)
			(effects
				(font
					(size 1.27 1.27)
					(thickness 0.15)
				)
				(justify right)
			)
		)
		(property "Value" "C_220n_0402"
			(at 247.65 233.68 0)
			(effects
				(font
					(size 1.27 1.27)
					(thickness 0.15)
				)
				(justify left bottom)
				(hide yes)
			)
		)
		(property "Footprint" "antmicro-footprints:C_0402_1005Metric"
			(at 250.19 233.68 0)
			(effects
				(font
					(size 1.27 1.27)
					(thickness 0.15)
				)
				(justify left bottom)
				(hide yes)
			)
		)
		(property "Datasheet" "https://www.yageo.com/en/Chart/Download/pdf/CC0402KRX5R6BB224"
			(at 252.73 233.68 0)
			(effects
				(font
					(size 1.27 1.27)
					(thickness 0.15)
				)
				(justify left bottom)
				(hide yes)
			)
		)
		(property "Description" "SMD Multilayer Ceramic Capacitor, 0.22 µF, 10 V, 0402 [1005 Metric], ± 10%, X5R, CC Series"
			(at 237.49 254 0)
			(effects
				(font
					(size 1.27 1.27)
				)
				(hide yes)
			)
		)
		(property "MPN" "CC0402KRX5R6BB224"
			(at 255.27 233.68 0)
			(effects
				(font
					(size 1.27 1.27)
					(thickness 0.15)
				)
				(justify left bottom)
				(hide yes)
			)
		)
		(property "Manufacturer" "YAGEO"
			(at 257.81 233.68 0)
			(effects
				(font
					(size 1.27 1.27)
					(thickness 0.15)
				)
				(justify left bottom)
				(hide yes)
			)
		)
		(property "License" "Apache-2.0"
			(at 260.35 233.68 0)
			(effects
				(font
					(size 1.27 1.27)
					(thickness 0.15)
				)
				(justify left bottom)
				(hide yes)
			)
		)
		(property "Val" "220n"
			(at 240.665 252.7235 90)
			(effects
				(font
					(size 1.27 1.27)
					(thickness 0.15)
				)
				(justify right)
			)
		)
		(property "Voltage" ""
			(at 265.43 233.68 0)
			(effects
				(font
					(size 1.27 1.27)
				)
				(justify left bottom)
				(hide yes)
			)
		)
		(property "Dielectric" ""
			(at 267.97 233.68 0)
			(effects
				(font
					(size 1.27 1.27)
				)
				(justify left bottom)
				(hide yes)
			)
		)
		(property "Author" "Antmicro"
			(at 262.89 233.68 0)
			(effects
				(font
					(size 1.27 1.27)
					(thickness 0.15)
				)
				(justify left bottom)
				(hide yes)
			)
		)
		(pin "1"
		)
		(pin "2"
		)
		(instances
			(project "thunderbolt-gpu-adapter"
				(path ""
					(reference "C31")
					(unit 1)
				)
			)
			(project "thunderbolt-to-10gbe-adapter"
				(path ""
					(reference "C23")
					(unit 1)
				)
			)
		)
	)
	(symbol
		(lib_id "antmicroResistors0402:R_10k_0402")
		(at 264.16 217.17 90)
		(unit 1)
		(exclude_from_sim no)
		(in_bom yes)
		(on_board yes)
		(dnp no)
		(property "Reference" "R31"
			(at 265.43 213.36 90)
			(effects
				(font
					(size 1.27 1.27)
					(thickness 0.15)
				)
				(justify right)
			)
		)
		(property "Value" "R_10k_0402"
			(at 276.86 196.85 0)
			(effects
				(font
					(size 1.27 1.27)
					(thickness 0.15)
				)
				(justify left bottom)
				(hide yes)
			)
		)
		(property "Footprint" "antmicro-footprints:R_0402_1005Metric"
			(at 279.4 196.85 0)
			(effects
				(font
					(size 1.27 1.27)
					(thickness 0.15)
				)
				(justify left bottom)
				(hide yes)
			)
		)
		(property "Datasheet" "https://www.bourns.com/docs/product-datasheets/cr.pdf"
			(at 281.94 196.85 0)
			(effects
				(font
					(size 1.27 1.27)
					(thickness 0.15)
				)
				(justify left bottom)
				(hide yes)
			)
		)
		(property "Description" "SMD Chip Resistor, 10 kohm, ± 1%, 62.5 mW, 0402 [1005 Metric], Thick Film, General Purpose"
			(at 264.16 217.17 0)
			(effects
				(font
					(size 1.27 1.27)
				)
				(hide yes)
			)
		)
		(property "MPN" "CR0402-FX-1002GLF"
			(at 284.48 196.85 0)
			(effects
				(font
					(size 1.27 1.27)
					(thickness 0.15)
				)
				(justify left bottom)
				(hide yes)
			)
		)
		(property "Manufacturer" "Bourns"
			(at 287.02 196.85 0)
			(effects
				(font
					(size 1.27 1.27)
					(thickness 0.15)
				)
				(justify left bottom)
				(hide yes)
			)
		)
		(property "License" "Apache-2.0"
			(at 289.56 196.85 0)
			(effects
				(font
					(size 1.27 1.27)
					(thickness 0.15)
				)
				(justify left bottom)
				(hide yes)
			)
		)
		(property "Val" "10k"
			(at 265.43 215.9 90)
			(effects
				(font
					(size 1.27 1.27)
					(thickness 0.15)
				)
				(justify right)
			)
		)
		(property "Tolerance" "1%"
			(at 274.32 196.85 0)
			(effects
				(font
					(size 1.27 1.27)
				)
				(justify left bottom)
				(hide yes)
			)
		)
		(property "Author" "Antmicro"
			(at 292.1 196.85 0)
			(effects
				(font
					(size 1.27 1.27)
					(thickness 0.15)
				)
				(justify left bottom)
				(hide yes)
			)
		)
		(pin "1"
		)
		(pin "2"
		)
		(instances
			(project "thunderbolt-gpu-adapter"
				(path ""
					(reference "R39")
					(unit 1)
				)
			)
			(project "thunderbolt-to-10gbe-adapter"
				(path ""
					(reference "R31")
					(unit 1)
				)
			)
		)
	)
	(symbol
		(lib_id "antmicropower:GND")
		(at 252.73 137.16 0)
		(unit 1)
		(exclude_from_sim no)
		(in_bom yes)
		(on_board yes)
		(dnp no)
		(property "Reference" "#PWR038"
			(at 252.73 143.51 0)
			(effects
				(font
					(size 1.27 1.27)
				)
				(hide yes)
			)
		)
		(property "Value" "GND"
			(at 252.73 140.97 0)
			(effects
				(font
					(size 1.27 1.27)
				)
			)
		)
		(property "Footprint" ""
			(at 252.73 137.16 0)
			(effects
				(font
					(size 1.27 1.27)
				)
				(hide yes)
			)
		)
		(property "Datasheet" ""
			(at 252.73 137.16 0)
			(effects
				(font
					(size 1.27 1.27)
				)
				(hide yes)
			)
		)
		(property "Description" ""
			(at 252.73 137.16 0)
			(effects
				(font
					(size 1.27 1.27)
				)
				(hide yes)
			)
		)
		(property "Author" "Antmicro"
			(at 261.62 144.78 0)
			(effects
				(font
					(size 1.27 1.27)
					(thickness 0.15)
				)
				(justify left bottom)
				(hide yes)
			)
		)
		(property "License" "Apache-2.0"
			(at 261.62 147.32 0)
			(effects
				(font
					(size 1.27 1.27)
					(thickness 0.15)
				)
				(justify left bottom)
				(hide yes)
			)
		)
		(pin "1"
		)
		(instances
			(project "thunderbolt-gpu-adapter"
				(path ""
					(reference "#PWR059")
					(unit 1)
				)
			)
			(project "thunderbolt-to-10gbe-adapter"
				(path ""
					(reference "#PWR038")
					(unit 1)
				)
			)
		)
	)
	(symbol
		(lib_id "antmicropower:GND")
		(at 229.87 77.47 0)
		(mirror y)
		(unit 1)
		(exclude_from_sim no)
		(in_bom yes)
		(on_board yes)
		(dnp no)
		(property "Reference" "#PWR032"
			(at 220.98 80.01 0)
			(effects
				(font
					(size 1.27 1.27)
					(thickness 0.15)
				)
				(justify left bottom)
				(hide yes)
			)
		)
		(property "Value" "GND"
			(at 229.87 81.28 0)
			(effects
				(font
					(size 1.27 1.27)
					(thickness 0.15)
				)
			)
		)
		(property "Footprint" ""
			(at 220.98 85.09 0)
			(effects
				(font
					(size 1.27 1.27)
					(thickness 0.15)
				)
				(justify left bottom)
				(hide yes)
			)
		)
		(property "Datasheet" ""
			(at 220.98 90.17 0)
			(effects
				(font
					(size 1.27 1.27)
					(thickness 0.15)
				)
				(justify left bottom)
				(hide yes)
			)
		)
		(property "Description" ""
			(at 229.87 77.47 0)
			(effects
				(font
					(size 1.27 1.27)
				)
				(hide yes)
			)
		)
		(property "Author" "Antmicro"
			(at 220.98 85.09 0)
			(effects
				(font
					(size 1.27 1.27)
					(thickness 0.15)
				)
				(justify left bottom)
				(hide yes)
			)
		)
		(property "License" "Apache-2.0"
			(at 220.98 87.63 0)
			(effects
				(font
					(size 1.27 1.27)
					(thickness 0.15)
				)
				(justify left bottom)
				(hide yes)
			)
		)
		(pin "1"
		)
		(instances
			(project "thunderbolt-to-10gbe-adapter"
				(path ""
					(reference "#PWR032")
					(unit 1)
				)
			)
		)
	)
	(symbol
		(lib_id "antmicroCapacitors0402:C_4u7_25V_0402")
		(at 157.48 129.54 0)
		(unit 1)
		(exclude_from_sim no)
		(in_bom yes)
		(on_board yes)
		(dnp no)
		(fields_autoplaced yes)
		(property "Reference" "C12"
			(at 157.48 128.27 0)
			(effects
				(font
					(size 1.27 1.27)
					(thickness 0.15)
				)
			)
		)
		(property "Value" "C_4u7_25V_0402"
			(at 177.8 139.7 0)
			(effects
				(font
					(size 1.27 1.27)
					(thickness 0.15)
				)
				(justify left bottom)
				(hide yes)
			)
		)
		(property "Footprint" "antmicro-footprints:C_0402_1005Metric"
			(at 177.8 142.24 0)
			(effects
				(font
					(size 1.27 1.27)
					(thickness 0.15)
				)
				(justify left bottom)
				(hide yes)
			)
		)
		(property "Datasheet" "https://www.murata.com/products/productdetail?partno=GRM155C61E475ME15%23"
			(at 177.8 144.78 0)
			(effects
				(font
					(size 1.27 1.27)
					(thickness 0.15)
				)
				(justify left bottom)
				(hide yes)
			)
		)
		(property "Description" "SMD Multilayer Ceramic Capacitor"
			(at 157.48 129.54 0)
			(effects
				(font
					(size 1.27 1.27)
				)
				(hide yes)
			)
		)
		(property "MPN" "GRM155C61E475ME15J"
			(at 177.8 147.32 0)
			(effects
				(font
					(size 1.27 1.27)
					(thickness 0.15)
				)
				(justify left bottom)
				(hide yes)
			)
		)
		(property "Manufacturer" "Murata"
			(at 177.8 149.86 0)
			(effects
				(font
					(size 1.27 1.27)
					(thickness 0.15)
				)
				(justify left bottom)
				(hide yes)
			)
		)
		(property "License" "Apache-2.0"
			(at 177.8 152.4 0)
			(effects
				(font
					(size 1.27 1.27)
					(thickness 0.15)
				)
				(justify left bottom)
				(hide yes)
			)
		)
		(property "Val" "4u7"
			(at 162.56 128.27 0)
			(effects
				(font
					(size 1.27 1.27)
					(thickness 0.15)
				)
			)
		)
		(property "Voltage" "25V"
			(at 161.29 129.54 0)
			(effects
				(font
					(size 1.27 1.27)
				)
				(justify left bottom)
				(hide yes)
			)
		)
		(property "Dielectric" "X5S"
			(at 177.8 160.02 0)
			(effects
				(font
					(size 1.27 1.27)
				)
				(justify left bottom)
				(hide yes)
			)
		)
		(property "Author" "Antmicro"
			(at 177.8 154.94 0)
			(effects
				(font
					(size 1.27 1.27)
					(thickness 0.15)
				)
				(justify left bottom)
				(hide yes)
			)
		)
		(pin "1"
		)
		(pin "2"
		)
		(instances
			(project "thunderbolt-to-10gbe-adapter"
				(path ""
					(reference "C12")
					(unit 1)
				)
			)
		)
	)
	(symbol
		(lib_id "antmicropower:GND")
		(at 266.7 77.47 0)
		(unit 1)
		(exclude_from_sim no)
		(in_bom yes)
		(on_board yes)
		(dnp no)
		(fields_autoplaced yes)
		(property "Reference" "#PWR050"
			(at 266.7 83.82 0)
			(effects
				(font
					(size 1.27 1.27)
				)
				(hide yes)
			)
		)
		(property "Value" "GND"
			(at 266.7 81.28 0)
			(effects
				(font
					(size 1.27 1.27)
				)
			)
		)
		(property "Footprint" ""
			(at 266.7 77.47 0)
			(effects
				(font
					(size 1.27 1.27)
				)
				(hide yes)
			)
		)
		(property "Datasheet" ""
			(at 266.7 77.47 0)
			(effects
				(font
					(size 1.27 1.27)
				)
				(hide yes)
			)
		)
		(property "Description" ""
			(at 266.7 77.47 0)
			(effects
				(font
					(size 1.27 1.27)
				)
				(hide yes)
			)
		)
		(property "Author" "Antmicro"
			(at 275.59 85.09 0)
			(effects
				(font
					(size 1.27 1.27)
					(thickness 0.15)
				)
				(justify left bottom)
				(hide yes)
			)
		)
		(property "License" "Apache-2.0"
			(at 275.59 87.63 0)
			(effects
				(font
					(size 1.27 1.27)
					(thickness 0.15)
				)
				(justify left bottom)
				(hide yes)
			)
		)
		(pin "1"
		)
		(instances
			(project "thunderbolt-to-10gbe-adapter"
				(path ""
					(reference "#PWR050")
					(unit 1)
				)
			)
		)
	)
	(symbol
		(lib_id "antmicroResistors0402:R_15k_0.1%_0402")
		(at 240.03 241.3 0)
		(unit 1)
		(exclude_from_sim no)
		(in_bom yes)
		(on_board yes)
		(dnp no)
		(property "Reference" "R29"
			(at 238.125 240.03 0)
			(effects
				(font
					(size 1.27 1.27)
					(thickness 0.15)
				)
			)
		)
		(property "Value" "R_15k_0.1%_0402"
			(at 260.35 254 0)
			(effects
				(font
					(size 1.27 1.27)
					(thickness 0.15)
				)
				(justify left bottom)
				(hide yes)
			)
		)
		(property "Footprint" "antmicro-footprints:R_0402_1005Metric"
			(at 260.35 256.54 0)
			(effects
				(font
					(size 1.27 1.27)
					(thickness 0.15)
				)
				(justify left bottom)
				(hide yes)
			)
		)
		(property "Datasheet" "https://www.mouser.com/datasheet/2/315/AOA0000C307-1149632.pdf"
			(at 260.35 259.08 0)
			(effects
				(font
					(size 1.27 1.27)
					(thickness 0.15)
				)
				(justify left bottom)
				(hide yes)
			)
		)
		(property "Description" "SMD Chip Resistor, 15 kohm, ± 0.1%, 62.5 mW, 0402 [1005 Metric], Metal Film (Thin Film)"
			(at 240.03 241.3 0)
			(effects
				(font
					(size 1.27 1.27)
				)
				(hide yes)
			)
		)
		(property "MPN" "ERA-2ARB153X"
			(at 260.35 261.62 0)
			(effects
				(font
					(size 1.27 1.27)
					(thickness 0.15)
				)
				(justify left bottom)
				(hide yes)
			)
		)
		(property "Manufacturer" "Panasonic"
			(at 260.35 264.16 0)
			(effects
				(font
					(size 1.27 1.27)
					(thickness 0.15)
				)
				(justify left bottom)
				(hide yes)
			)
		)
		(property "License" "Apache-2.0"
			(at 260.35 266.7 0)
			(effects
				(font
					(size 1.27 1.27)
					(thickness 0.15)
				)
				(justify left bottom)
				(hide yes)
			)
		)
		(property "Val" "15k"
			(at 246.38 240.03 0)
			(effects
				(font
					(size 1.27 1.27)
					(thickness 0.15)
				)
			)
		)
		(property "Tolerance" "0.1%"
			(at 242.57 245.11 0)
			(effects
				(font
					(size 1.27 1.27)
				)
				(hide yes)
			)
		)
		(property "Author" "Antmicro"
			(at 260.35 269.24 0)
			(effects
				(font
					(size 1.27 1.27)
					(thickness 0.15)
				)
				(justify left bottom)
				(hide yes)
			)
		)
		(pin "1"
		)
		(pin "2"
		)
		(instances
			(project "thunderbolt-gpu-adapter"
				(path ""
					(reference "R35")
					(unit 1)
				)
			)
			(project "thunderbolt-to-10gbe-adapter"
				(path ""
					(reference "R29")
					(unit 1)
				)
			)
		)
	)
	(symbol
		(lib_id "antmicroDiodesZenerSingle:MM3Z3V3C")
		(at 135.89 64.77 270)
		(unit 1)
		(exclude_from_sim no)
		(in_bom yes)
		(on_board yes)
		(dnp no)
		(fields_autoplaced yes)
		(property "Reference" "D3"
			(at 138.43 66.04 90)
			(effects
				(font
					(size 1.27 1.27)
					(thickness 0.15)
				)
				(justify left)
			)
		)
		(property "Value" "MM3Z3V3C"
			(at 133.35 64.135 0)
			(effects
				(font
					(size 1.27 1.27)
					(thickness 0.15)
				)
				(justify left)
				(hide yes)
			)
		)
		(property "Footprint" "antmicro-footprints:D_SOD-323F"
			(at 125.73 87.63 0)
			(effects
				(font
					(size 1.27 1.27)
					(thickness 0.15)
				)
				(justify left bottom)
				(hide yes)
			)
		)
		(property "Datasheet" "https://www.onsemi.com/download/data-sheet/pdf/mm3z9v1c-d.pdf"
			(at 123.19 87.63 0)
			(effects
				(font
					(size 1.27 1.27)
					(thickness 0.15)
				)
				(justify left bottom)
				(hide yes)
			)
		)
		(property "Description" "Zener Single Diode, 3.3 V, 200 mW, SOD-323F, 2 Pins, 150 °C, Surface Mount"
			(at 135.89 64.77 0)
			(effects
				(font
					(size 1.27 1.27)
				)
				(hide yes)
			)
		)
		(property "MPN" "MM3Z3V3C"
			(at 138.43 68.58 90)
			(effects
				(font
					(size 1.27 1.27)
					(thickness 0.15)
				)
				(justify left)
			)
		)
		(property "Manufacturer" "ON Semiconductor"
			(at 118.11 87.63 0)
			(effects
				(font
					(size 1.27 1.27)
					(thickness 0.15)
				)
				(justify left bottom)
				(hide yes)
			)
		)
		(property "License" "Apache-2.0"
			(at 113.03 87.63 0)
			(effects
				(font
					(size 1.27 1.27)
					(thickness 0.15)
				)
				(justify left bottom)
				(hide yes)
			)
		)
		(property "Author" "Antmicro"
			(at 115.57 87.63 0)
			(effects
				(font
					(size 1.27 1.27)
					(thickness 0.15)
				)
				(justify left bottom)
				(hide yes)
			)
		)
		(pin "2"
		)
		(pin "1"
		)
		(instances
			(project "thunderbolt-to-10gbe-adapter"
				(path ""
					(reference "D3")
					(unit 1)
				)
			)
		)
	)
	(symbol
		(lib_id "antmicroCapacitors0402:C_1u_25V_0402")
		(at 257.81 138.43 90)
		(unit 1)
		(exclude_from_sim no)
		(in_bom yes)
		(on_board yes)
		(dnp no)
		(property "Reference" "C28"
			(at 259.588 134.62 90)
			(effects
				(font
					(size 1.27 1.27)
					(thickness 0.15)
				)
				(justify right)
			)
		)
		(property "Value" "C_1u_25V_0402"
			(at 267.97 118.11 0)
			(effects
				(font
					(size 1.27 1.27)
					(thickness 0.15)
				)
				(justify left bottom)
				(hide yes)
			)
		)
		(property "Footprint" "antmicro-footprints:C_0402_1005Metric"
			(at 270.51 118.11 0)
			(effects
				(font
					(size 1.27 1.27)
					(thickness 0.15)
				)
				(justify left bottom)
				(hide yes)
			)
		)
		(property "Datasheet" "https://www.murata.com/products/productdetail?partno=GRM155R61E105KE11%23"
			(at 273.05 118.11 0)
			(effects
				(font
					(size 1.27 1.27)
					(thickness 0.15)
				)
				(justify left bottom)
				(hide yes)
			)
		)
		(property "Description" "SMD Multilayer Ceramic Capacitor, 1 µF, 25 V, 0402 [1005 Metric], ± 10%, X5R, GRM Series"
			(at 290.83 118.11 0)
			(effects
				(font
					(size 1.27 1.27)
				)
				(justify left bottom)
				(hide yes)
			)
		)
		(property "MPN" "GRM155R61E105KE11J"
			(at 275.59 118.11 0)
			(effects
				(font
					(size 1.27 1.27)
					(thickness 0.15)
				)
				(justify left bottom)
				(hide yes)
			)
		)
		(property "Manufacturer" "Murata"
			(at 278.13 118.11 0)
			(effects
				(font
					(size 1.27 1.27)
					(thickness 0.15)
				)
				(justify left bottom)
				(hide yes)
			)
		)
		(property "License" "Apache-2.0"
			(at 280.67 118.11 0)
			(effects
				(font
					(size 1.27 1.27)
					(thickness 0.15)
				)
				(justify left bottom)
				(hide yes)
			)
		)
		(property "Author" "Antmicro"
			(at 283.21 118.11 0)
			(effects
				(font
					(size 1.27 1.27)
					(thickness 0.15)
				)
				(justify left bottom)
				(hide yes)
			)
		)
		(property "Val" "1u"
			(at 259.588 137.16 90)
			(effects
				(font
					(size 1.27 1.27)
					(thickness 0.15)
				)
				(justify right)
			)
		)
		(property "Voltage" "25V"
			(at 285.75 118.11 0)
			(effects
				(font
					(size 1.27 1.27)
				)
				(justify left bottom)
				(hide yes)
			)
		)
		(property "Dielectric" "X5R"
			(at 288.29 118.11 0)
			(effects
				(font
					(size 1.27 1.27)
				)
				(justify left bottom)
				(hide yes)
			)
		)
		(pin "2"
		)
		(pin "1"
		)
		(instances
			(project "thunderbolt-to-10gbe-adapter"
				(path ""
					(reference "C28")
					(unit 1)
				)
			)
		)
	)
	(symbol
		(lib_id "antmicroCapacitorspol:C_Pol_330u_6.3V_KEMET-T520-B")
		(at 288.29 66.04 270)
		(unit 1)
		(exclude_from_sim no)
		(in_bom yes)
		(on_board yes)
		(dnp no)
		(fields_autoplaced yes)
		(property "Reference" "C32"
			(at 285.75 66.7766 90)
			(effects
				(font
					(size 1.27 1.27)
					(thickness 0.15)
				)
				(justify right)
			)
		)
		(property "Value" "C_Pol_330u_6.3V_KEMET-T520-B"
			(at 285.75 80.01 0)
			(effects
				(font
					(size 1.27 1.27)
					(thickness 0.15)
				)
				(justify left bottom)
				(hide yes)
			)
		)
		(property "Footprint" "antmicro-footprints:C_Pol_EIA-B"
			(at 280.67 80.01 0)
			(effects
				(font
					(size 1.27 1.27)
					(thickness 0.15)
				)
				(justify left bottom)
				(hide yes)
			)
		)
		(property "Datasheet" "https://www.kemet.com/en/us/capacitors/product/T520B337M006ATE040.html"
			(at 278.13 80.01 0)
			(effects
				(font
					(size 1.27 1.27)
					(thickness 0.15)
				)
				(justify left bottom)
				(hide yes)
			)
		)
		(property "Description" "Tantalum Polymer Capacitor, KO-CAP®, 330 µF, ± 20%, 6.3 V, B, 0.04 ohm, 1411 [3528 Metric]"
			(at 288.29 66.04 0)
			(effects
				(font
					(size 1.27 1.27)
				)
				(hide yes)
			)
		)
		(property "Val" "330u"
			(at 285.75 69.3166 90)
			(effects
				(font
					(size 1.27 1.27)
					(thickness 0.15)
				)
				(justify right)
			)
		)
		(property "MPN" "T520B337M006ATE040"
			(at 275.59 80.01 0)
			(effects
				(font
					(size 1.27 1.27)
					(thickness 0.15)
				)
				(justify left bottom)
				(hide yes)
			)
		)
		(property "Manufacturer" "KEMET"
			(at 273.05 80.01 0)
			(effects
				(font
					(size 1.27 1.27)
					(thickness 0.15)
				)
				(justify left bottom)
				(hide yes)
			)
		)
		(property "License" "Apache-2.0"
			(at 270.51 80.01 0)
			(effects
				(font
					(size 1.27 1.27)
					(thickness 0.15)
				)
				(justify left bottom)
				(hide yes)
			)
		)
		(property "Author" "Antmicro"
			(at 267.97 80.01 0)
			(effects
				(font
					(size 1.27 1.27)
					(thickness 0.15)
				)
				(justify left bottom)
				(hide yes)
			)
		)
		(property "Voltage" "6.3V"
			(at 265.43 80.01 0)
			(effects
				(font
					(size 1.27 1.27)
				)
				(justify left bottom)
				(hide yes)
			)
		)
		(property "Dielectric" "template_dielectric"
			(at 262.89 80.01 0)
			(effects
				(font
					(size 1.27 1.27)
				)
				(justify left bottom)
				(hide yes)
			)
		)
		(pin "1"
		)
		(pin "2"
		)
		(instances
			(project "thunderbolt-to-10gbe-adapter"
				(path ""
					(reference "C32")
					(unit 1)
				)
			)
		)
	)
	(symbol
		(lib_id "antmicroFixedInductors:L_2u2_9.7A_Coilcraft-XAL5030")
		(at 189.23 59.69 0)
		(unit 1)
		(exclude_from_sim no)
		(in_bom yes)
		(on_board yes)
		(dnp no)
		(fields_autoplaced yes)
		(property "Reference" "L1"
			(at 191.77 54.61 0)
			(effects
				(font
					(size 1.27 1.27)
					(thickness 0.15)
				)
			)
		)
		(property "Value" "L_2u2_9.7A_Coilcraft-XAL5030"
			(at 203.2 62.23 0)
			(effects
				(font
					(size 1.27 1.27)
					(thickness 0.15)
				)
				(justify left bottom)
				(hide yes)
			)
		)
		(property "Footprint" "antmicro-footprints:L_Coilcraft-XAL5030"
			(at 203.2 67.31 0)
			(effects
				(font
					(size 1.27 1.27)
					(thickness 0.15)
				)
				(justify left bottom)
				(hide yes)
			)
		)
		(property "Datasheet" "https://www.coilcraft.com/getmedia/49bc46c8-4b2c-45b9-9b6c-2eaa235ea698/xal50xx.pdf"
			(at 203.2 69.85 0)
			(effects
				(font
					(size 1.27 1.27)
					(thickness 0.15)
				)
				(justify left bottom)
				(hide yes)
			)
		)
		(property "Description" "Power Inductor (SMT), 2.2 µH, 9.7 A, Shielded, 9.2 A, XAL5030"
			(at 189.23 59.69 0)
			(effects
				(font
					(size 1.27 1.27)
				)
				(hide yes)
			)
		)
		(property "Val" "2u2/9.7A"
			(at 191.77 57.15 0)
			(effects
				(font
					(size 1.27 1.27)
					(thickness 0.15)
				)
			)
		)
		(property "Manufacturer" "Coilcraft"
			(at 203.2 72.39 0)
			(effects
				(font
					(size 1.27 1.27)
					(thickness 0.15)
				)
				(justify left bottom)
				(hide yes)
			)
		)
		(property "MPN" "XAL5030-222MEC"
			(at 203.2 74.93 0)
			(effects
				(font
					(size 1.27 1.27)
					(thickness 0.15)
				)
				(justify left bottom)
				(hide yes)
			)
		)
		(property "ISat" "9.2 A"
			(at 203.2 76.2 0)
			(effects
				(font
					(size 1.27 1.27)
				)
				(justify left)
				(hide yes)
			)
		)
		(property "IMax" "9.7 A"
			(at 203.2 80.01 0)
			(effects
				(font
					(size 1.27 1.27)
					(thickness 0.15)
				)
				(justify left bottom)
				(hide yes)
			)
		)
		(property "Size" "5.28x5.48"
			(at 203.2 82.55 0)
			(effects
				(font
					(size 1.27 1.27)
					(thickness 0.15)
				)
				(justify left bottom)
				(hide yes)
			)
		)
		(property "Author" "Antmicro"
			(at 203.2 85.09 0)
			(effects
				(font
					(size 1.27 1.27)
					(thickness 0.15)
				)
				(justify left bottom)
				(hide yes)
			)
		)
		(property "License" "Apache-2.0"
			(at 203.2 87.63 0)
			(effects
				(font
					(size 1.27 1.27)
					(thickness 0.15)
				)
				(justify left bottom)
				(hide yes)
			)
		)
		(pin "1"
		)
		(pin "2"
		)
		(instances
			(project "thunderbolt-to-10gbe-adapter"
				(path ""
					(reference "L1")
					(unit 1)
				)
			)
		)
	)
	(symbol
		(lib_id "antmicropower:GND")
		(at 237.49 256.54 0)
		(unit 1)
		(exclude_from_sim no)
		(in_bom yes)
		(on_board yes)
		(dnp no)
		(property "Reference" "#PWR033"
			(at 237.49 262.89 0)
			(effects
				(font
					(size 1.27 1.27)
				)
				(hide yes)
			)
		)
		(property "Value" "GND"
			(at 237.49 260.35 0)
			(effects
				(font
					(size 1.27 1.27)
				)
			)
		)
		(property "Footprint" ""
			(at 237.49 256.54 0)
			(effects
				(font
					(size 1.27 1.27)
				)
				(hide yes)
			)
		)
		(property "Datasheet" ""
			(at 237.49 256.54 0)
			(effects
				(font
					(size 1.27 1.27)
				)
				(hide yes)
			)
		)
		(property "Description" ""
			(at 237.49 256.54 0)
			(effects
				(font
					(size 1.27 1.27)
				)
				(hide yes)
			)
		)
		(property "Author" "Antmicro"
			(at 246.38 264.16 0)
			(effects
				(font
					(size 1.27 1.27)
					(thickness 0.15)
				)
				(justify left bottom)
				(hide yes)
			)
		)
		(property "License" "Apache-2.0"
			(at 246.38 266.7 0)
			(effects
				(font
					(size 1.27 1.27)
					(thickness 0.15)
				)
				(justify left bottom)
				(hide yes)
			)
		)
		(pin "1"
		)
		(instances
			(project "thunderbolt-gpu-adapter"
				(path ""
					(reference "#PWR043")
					(unit 1)
				)
			)
			(project "thunderbolt-to-10gbe-adapter"
				(path ""
					(reference "#PWR033")
					(unit 1)
				)
			)
		)
	)
	(symbol
		(lib_id "antmicroCapacitorsmisc:C_22u_25V_0805")
		(at 119.38 50.8 90)
		(unit 1)
		(exclude_from_sim no)
		(in_bom yes)
		(on_board yes)
		(dnp no)
		(property "Reference" "C7"
			(at 121.158 45.7201 90)
			(effects
				(font
					(size 1.27 1.27)
					(thickness 0.15)
				)
				(justify right)
			)
		)
		(property "Value" "C_22u_25V_0805"
			(at 129.54 30.48 0)
			(effects
				(font
					(size 1.27 1.27)
					(thickness 0.15)
				)
				(justify left bottom)
				(hide yes)
			)
		)
		(property "Footprint" "antmicro-footprints:C_0805_2012Metric"
			(at 132.08 30.48 0)
			(effects
				(font
					(size 1.27 1.27)
					(thickness 0.15)
				)
				(justify left bottom)
				(hide yes)
			)
		)
		(property "Datasheet" "https://product.samsungsem.com/mlcc/CL21A226MAYNNN.do"
			(at 134.62 30.48 0)
			(effects
				(font
					(size 1.27 1.27)
					(thickness 0.15)
				)
				(justify left bottom)
				(hide yes)
			)
		)
		(property "Description" "SMT Multilayer Ceramic Capacitor, 22uF, +/-20%, 25V, X5R, 0805 [2012 Metric]"
			(at 152.4 30.48 0)
			(effects
				(font
					(size 1.27 1.27)
				)
				(justify left bottom)
				(hide yes)
			)
		)
		(property "MPN" "CL21A226MAYNNNE"
			(at 137.16 30.48 0)
			(effects
				(font
					(size 1.27 1.27)
					(thickness 0.15)
				)
				(justify left bottom)
				(hide yes)
			)
		)
		(property "Manufacturer" "Samsung Electro-Mechanics"
			(at 139.7 30.48 0)
			(effects
				(font
					(size 1.27 1.27)
					(thickness 0.15)
				)
				(justify left bottom)
				(hide yes)
			)
		)
		(property "License" "Apache-2.0"
			(at 142.24 30.48 0)
			(effects
				(font
					(size 1.27 1.27)
					(thickness 0.15)
				)
				(justify left bottom)
				(hide yes)
			)
		)
		(property "Author" "Antmicro"
			(at 144.78 30.48 0)
			(effects
				(font
					(size 1.27 1.27)
					(thickness 0.15)
				)
				(justify left bottom)
				(hide yes)
			)
		)
		(property "Val" "22u"
			(at 121.158 48.2601 90)
			(effects
				(font
					(size 1.27 1.27)
					(thickness 0.15)
				)
				(justify right)
			)
		)
		(property "Voltage" "25V"
			(at 121.158 50.8 90)
			(effects
				(font
					(size 1.27 1.27)
				)
				(justify right)
			)
		)
		(property "Dielectric" "X5R"
			(at 149.86 30.48 0)
			(effects
				(font
					(size 1.27 1.27)
				)
				(justify left bottom)
				(hide yes)
			)
		)
		(property "Public" "False"
			(at 152.4 30.48 0)
			(effects
				(font
					(size 1.27 1.27)
				)
				(justify left bottom)
				(hide yes)
			)
		)
		(pin "2"
		)
		(pin "1"
		)
		(instances
			(project "thunderbolt-to-10gbe-adapter"
				(path ""
					(reference "C7")
					(unit 1)
				)
			)
		)
	)
	(symbol
		(lib_id "antmicropower:GND")
		(at 288.29 77.47 0)
		(unit 1)
		(exclude_from_sim no)
		(in_bom yes)
		(on_board yes)
		(dnp no)
		(fields_autoplaced yes)
		(property "Reference" "#PWR057"
			(at 288.29 83.82 0)
			(effects
				(font
					(size 1.27 1.27)
				)
				(hide yes)
			)
		)
		(property "Value" "GND"
			(at 288.29 81.28 0)
			(effects
				(font
					(size 1.27 1.27)
				)
			)
		)
		(property "Footprint" ""
			(at 288.29 77.47 0)
			(effects
				(font
					(size 1.27 1.27)
				)
				(hide yes)
			)
		)
		(property "Datasheet" ""
			(at 288.29 77.47 0)
			(effects
				(font
					(size 1.27 1.27)
				)
				(hide yes)
			)
		)
		(property "Description" ""
			(at 288.29 77.47 0)
			(effects
				(font
					(size 1.27 1.27)
				)
				(hide yes)
			)
		)
		(property "Author" "Antmicro"
			(at 297.18 85.09 0)
			(effects
				(font
					(size 1.27 1.27)
					(thickness 0.15)
				)
				(justify left bottom)
				(hide yes)
			)
		)
		(property "License" "Apache-2.0"
			(at 297.18 87.63 0)
			(effects
				(font
					(size 1.27 1.27)
					(thickness 0.15)
				)
				(justify left bottom)
				(hide yes)
			)
		)
		(pin "1"
		)
		(instances
			(project "thunderbolt-to-10gbe-adapter"
				(path ""
					(reference "#PWR057")
					(unit 1)
				)
			)
		)
	)
	(symbol
		(lib_id "antmicropower:GND")
		(at 252.73 226.06 0)
		(unit 1)
		(exclude_from_sim no)
		(in_bom yes)
		(on_board yes)
		(dnp no)
		(property "Reference" "#PWR044"
			(at 252.73 232.41 0)
			(effects
				(font
					(size 1.27 1.27)
				)
				(hide yes)
			)
		)
		(property "Value" "GND"
			(at 252.73 229.87 0)
			(effects
				(font
					(size 1.27 1.27)
				)
			)
		)
		(property "Footprint" ""
			(at 252.73 226.06 0)
			(effects
				(font
					(size 1.27 1.27)
				)
				(hide yes)
			)
		)
		(property "Datasheet" ""
			(at 252.73 226.06 0)
			(effects
				(font
					(size 1.27 1.27)
				)
				(hide yes)
			)
		)
		(property "Description" ""
			(at 252.73 226.06 0)
			(effects
				(font
					(size 1.27 1.27)
				)
				(hide yes)
			)
		)
		(property "Author" "Antmicro"
			(at 261.62 233.68 0)
			(effects
				(font
					(size 1.27 1.27)
					(thickness 0.15)
				)
				(justify left bottom)
				(hide yes)
			)
		)
		(property "License" "Apache-2.0"
			(at 261.62 236.22 0)
			(effects
				(font
					(size 1.27 1.27)
					(thickness 0.15)
				)
				(justify left bottom)
				(hide yes)
			)
		)
		(pin "1"
		)
		(instances
			(project "thunderbolt-gpu-adapter"
				(path ""
					(reference "#PWR056")
					(unit 1)
				)
			)
			(project "thunderbolt-to-10gbe-adapter"
				(path ""
					(reference "#PWR044")
					(unit 1)
				)
			)
		)
	)
	(symbol
		(lib_id "antmicropower:GND")
		(at 252.73 199.39 0)
		(unit 1)
		(exclude_from_sim no)
		(in_bom yes)
		(on_board yes)
		(dnp no)
		(property "Reference" "#PWR042"
			(at 252.73 205.74 0)
			(effects
				(font
					(size 1.27 1.27)
				)
				(hide yes)
			)
		)
		(property "Value" "GND"
			(at 252.73 203.2 0)
			(effects
				(font
					(size 1.27 1.27)
				)
			)
		)
		(property "Footprint" ""
			(at 252.73 199.39 0)
			(effects
				(font
					(size 1.27 1.27)
				)
				(hide yes)
			)
		)
		(property "Datasheet" ""
			(at 252.73 199.39 0)
			(effects
				(font
					(size 1.27 1.27)
				)
				(hide yes)
			)
		)
		(property "Description" ""
			(at 252.73 199.39 0)
			(effects
				(font
					(size 1.27 1.27)
				)
				(hide yes)
			)
		)
		(property "Author" "Antmicro"
			(at 261.62 207.01 0)
			(effects
				(font
					(size 1.27 1.27)
					(thickness 0.15)
				)
				(justify left bottom)
				(hide yes)
			)
		)
		(property "License" "Apache-2.0"
			(at 261.62 209.55 0)
			(effects
				(font
					(size 1.27 1.27)
					(thickness 0.15)
				)
				(justify left bottom)
				(hide yes)
			)
		)
		(pin "1"
		)
		(instances
			(project "thunderbolt-gpu-adapter"
				(path ""
					(reference "#PWR046")
					(unit 1)
				)
			)
			(project "thunderbolt-to-10gbe-adapter"
				(path ""
					(reference "#PWR042")
					(unit 1)
				)
			)
		)
	)
	(symbol
		(lib_id "antmicropower:GND")
		(at 252.73 241.3 0)
		(unit 1)
		(exclude_from_sim no)
		(in_bom yes)
		(on_board yes)
		(dnp no)
		(property "Reference" "#PWR046"
			(at 252.73 247.65 0)
			(effects
				(font
					(size 1.27 1.27)
				)
				(hide yes)
			)
		)
		(property "Value" "GND"
			(at 252.73 245.11 0)
			(effects
				(font
					(size 1.27 1.27)
				)
			)
		)
		(property "Footprint" ""
			(at 252.73 241.3 0)
			(effects
				(font
					(size 1.27 1.27)
				)
				(hide yes)
			)
		)
		(property "Datasheet" ""
			(at 252.73 241.3 0)
			(effects
				(font
					(size 1.27 1.27)
				)
				(hide yes)
			)
		)
		(property "Description" ""
			(at 252.73 241.3 0)
			(effects
				(font
					(size 1.27 1.27)
				)
				(hide yes)
			)
		)
		(property "Author" "Antmicro"
			(at 261.62 248.92 0)
			(effects
				(font
					(size 1.27 1.27)
					(thickness 0.15)
				)
				(justify left bottom)
				(hide yes)
			)
		)
		(property "License" "Apache-2.0"
			(at 261.62 251.46 0)
			(effects
				(font
					(size 1.27 1.27)
					(thickness 0.15)
				)
				(justify left bottom)
				(hide yes)
			)
		)
		(pin "1"
		)
		(instances
			(project "thunderbolt-gpu-adapter"
				(path ""
					(reference "#PWR058")
					(unit 1)
				)
			)
			(project "thunderbolt-to-10gbe-adapter"
				(path ""
					(reference "#PWR046")
					(unit 1)
				)
			)
		)
	)
	(symbol
		(lib_id "antmicroResistors0402:R_2k2_0402")
		(at 144.78 151.13 90)
		(unit 1)
		(exclude_from_sim no)
		(in_bom yes)
		(on_board yes)
		(dnp no)
		(property "Reference" "R10"
			(at 146.05 147.32 90)
			(effects
				(font
					(size 1.27 1.27)
					(thickness 0.15)
				)
				(justify right)
			)
		)
		(property "Value" "R_2k2_0402"
			(at 157.48 130.81 0)
			(effects
				(font
					(size 1.27 1.27)
					(thickness 0.15)
				)
				(justify left bottom)
				(hide yes)
			)
		)
		(property "Footprint" "antmicro-footprints:R_0402_1005Metric"
			(at 160.02 130.81 0)
			(effects
				(font
					(size 1.27 1.27)
					(thickness 0.15)
				)
				(justify left bottom)
				(hide yes)
			)
		)
		(property "Datasheet" "https://www.bourns.com/docs/product-datasheets/cr.pdf"
			(at 162.56 130.81 0)
			(effects
				(font
					(size 1.27 1.27)
					(thickness 0.15)
				)
				(justify left bottom)
				(hide yes)
			)
		)
		(property "Description" "SMD Chip Resistor, 2.2 kohm, ± 1%, 62.5 mW, 0402 [1005 Metric], Thick Film, General Purpose"
			(at 144.78 151.13 0)
			(effects
				(font
					(size 1.27 1.27)
				)
				(hide yes)
			)
		)
		(property "MPN" "CR0402-FX-2201GLF"
			(at 165.1 130.81 0)
			(effects
				(font
					(size 1.27 1.27)
					(thickness 0.15)
				)
				(justify left bottom)
				(hide yes)
			)
		)
		(property "Manufacturer" "Bourns"
			(at 167.64 130.81 0)
			(effects
				(font
					(size 1.27 1.27)
					(thickness 0.15)
				)
				(justify left bottom)
				(hide yes)
			)
		)
		(property "License" "Apache-2.0"
			(at 170.18 130.81 0)
			(effects
				(font
					(size 1.27 1.27)
					(thickness 0.15)
				)
				(justify left bottom)
				(hide yes)
			)
		)
		(property "Val" "2k2"
			(at 146.05 149.86 90)
			(effects
				(font
					(size 1.27 1.27)
					(thickness 0.15)
				)
				(justify right)
			)
		)
		(property "Tolerance" "1%"
			(at 154.94 130.81 0)
			(effects
				(font
					(size 1.27 1.27)
				)
				(justify left bottom)
				(hide yes)
			)
		)
		(property "Author" "Antmicro"
			(at 172.72 130.81 0)
			(effects
				(font
					(size 1.27 1.27)
					(thickness 0.15)
				)
				(justify left bottom)
				(hide yes)
			)
		)
		(pin "1"
		)
		(pin "2"
		)
		(instances
			(project "thunderbolt-gpu-adapter"
				(path ""
					(reference "R5")
					(unit 1)
				)
			)
			(project "thunderbolt-to-10gbe-adapter"
				(path ""
					(reference "R10")
					(unit 1)
				)
			)
		)
	)
	(symbol
		(lib_id "antmicroCapacitors0603:C_22u_0603")
		(at 248.92 71.12 90)
		(unit 1)
		(exclude_from_sim no)
		(in_bom yes)
		(on_board yes)
		(dnp no)
		(fields_autoplaced yes)
		(property "Reference" "C26"
			(at 251.46 67.3036 90)
			(effects
				(font
					(size 1.27 1.27)
					(thickness 0.15)
				)
				(justify right)
			)
		)
		(property "Value" "C_22u_0603"
			(at 259.08 50.8 0)
			(effects
				(font
					(size 1.27 1.27)
					(thickness 0.15)
				)
				(justify left bottom)
				(hide yes)
			)
		)
		(property "Footprint" "antmicro-footprints:C_0603_1608Metric"
			(at 261.62 50.8 0)
			(effects
				(font
					(size 1.27 1.27)
					(thickness 0.15)
				)
				(justify left bottom)
				(hide yes)
			)
		)
		(property "Datasheet" "https://www.murata.com/products/productdetail?partno=GRM188R60J226MEA0%23"
			(at 264.16 50.8 0)
			(effects
				(font
					(size 1.27 1.27)
					(thickness 0.15)
				)
				(justify left bottom)
				(hide yes)
			)
		)
		(property "Description" "SMD Multilayer Ceramic Capacitor, 22 µF, 6.3 V, 0603 [1608 Metric], ± 20%, X5R, GRM Series"
			(at 248.92 71.12 0)
			(effects
				(font
					(size 1.27 1.27)
				)
				(hide yes)
			)
		)
		(property "MPN" "GRM188R60J226MEA0D"
			(at 266.7 50.8 0)
			(effects
				(font
					(size 1.27 1.27)
					(thickness 0.15)
				)
				(justify left bottom)
				(hide yes)
			)
		)
		(property "Manufacturer" "Murata"
			(at 269.24 50.8 0)
			(effects
				(font
					(size 1.27 1.27)
					(thickness 0.15)
				)
				(justify left bottom)
				(hide yes)
			)
		)
		(property "License" "Apache-2.0"
			(at 271.78 50.8 0)
			(effects
				(font
					(size 1.27 1.27)
					(thickness 0.15)
				)
				(justify left bottom)
				(hide yes)
			)
		)
		(property "Val" "22u"
			(at 251.46 69.8436 90)
			(effects
				(font
					(size 1.27 1.27)
					(thickness 0.15)
				)
				(justify right)
			)
		)
		(property "Voltage" ""
			(at 276.86 50.8 0)
			(effects
				(font
					(size 1.27 1.27)
				)
				(justify left bottom)
				(hide yes)
			)
		)
		(property "Dielectric" ""
			(at 279.4 50.8 0)
			(effects
				(font
					(size 1.27 1.27)
				)
				(justify left bottom)
				(hide yes)
			)
		)
		(property "Author" "Antmicro"
			(at 274.32 50.8 0)
			(effects
				(font
					(size 1.27 1.27)
					(thickness 0.15)
				)
				(justify left bottom)
				(hide yes)
			)
		)
		(pin "1"
		)
		(pin "2"
		)
		(instances
			(project "thunderbolt-to-10gbe-adapter"
				(path ""
					(reference "C26")
					(unit 1)
				)
			)
		)
	)
	(symbol
		(lib_id "antmicropower:GND")
		(at 267.97 140.97 0)
		(unit 1)
		(exclude_from_sim no)
		(in_bom yes)
		(on_board yes)
		(dnp no)
		(property "Reference" "#PWR052"
			(at 267.97 147.32 0)
			(effects
				(font
					(size 1.27 1.27)
				)
				(hide yes)
			)
		)
		(property "Value" "GND"
			(at 267.97 144.78 0)
			(effects
				(font
					(size 1.27 1.27)
				)
			)
		)
		(property "Footprint" ""
			(at 267.97 140.97 0)
			(effects
				(font
					(size 1.27 1.27)
				)
				(hide yes)
			)
		)
		(property "Datasheet" ""
			(at 267.97 140.97 0)
			(effects
				(font
					(size 1.27 1.27)
				)
				(hide yes)
			)
		)
		(property "Description" ""
			(at 267.97 140.97 0)
			(effects
				(font
					(size 1.27 1.27)
				)
				(hide yes)
			)
		)
		(property "Author" "Antmicro"
			(at 276.86 148.59 0)
			(effects
				(font
					(size 1.27 1.27)
					(thickness 0.15)
				)
				(justify left bottom)
				(hide yes)
			)
		)
		(property "License" "Apache-2.0"
			(at 276.86 151.13 0)
			(effects
				(font
					(size 1.27 1.27)
					(thickness 0.15)
				)
				(justify left bottom)
				(hide yes)
			)
		)
		(pin "1"
		)
		(instances
			(project "thunderbolt-gpu-adapter"
				(path ""
					(reference "#PWR069")
					(unit 1)
				)
			)
			(project "thunderbolt-to-10gbe-adapter"
				(path ""
					(reference "#PWR052")
					(unit 1)
				)
			)
		)
	)
	(symbol
		(lib_id "antmicropower:GND")
		(at 109.22 246.38 0)
		(unit 1)
		(exclude_from_sim no)
		(in_bom yes)
		(on_board yes)
		(dnp no)
		(property "Reference" "#PWR016"
			(at 109.22 252.73 0)
			(effects
				(font
					(size 1.27 1.27)
				)
				(hide yes)
			)
		)
		(property "Value" "GND"
			(at 109.22 250.19 0)
			(effects
				(font
					(size 1.27 1.27)
				)
			)
		)
		(property "Footprint" ""
			(at 109.22 246.38 0)
			(effects
				(font
					(size 1.27 1.27)
				)
				(hide yes)
			)
		)
		(property "Datasheet" ""
			(at 109.22 246.38 0)
			(effects
				(font
					(size 1.27 1.27)
				)
				(hide yes)
			)
		)
		(property "Description" ""
			(at 109.22 246.38 0)
			(effects
				(font
					(size 1.27 1.27)
				)
				(hide yes)
			)
		)
		(property "Author" "Antmicro"
			(at 118.11 254 0)
			(effects
				(font
					(size 1.27 1.27)
					(thickness 0.15)
				)
				(justify left bottom)
				(hide yes)
			)
		)
		(property "License" "Apache-2.0"
			(at 118.11 256.54 0)
			(effects
				(font
					(size 1.27 1.27)
					(thickness 0.15)
				)
				(justify left bottom)
				(hide yes)
			)
		)
		(pin "1"
		)
		(instances
			(project "thunderbolt-gpu-adapter"
				(path ""
					(reference "#PWR022")
					(unit 1)
				)
			)
			(project "thunderbolt-to-10gbe-adapter"
				(path ""
					(reference "#PWR016")
					(unit 1)
				)
			)
		)
	)
	(symbol
		(lib_id "antmicroTestPoints:TP_0.75mm_SMD")
		(at 93.98 41.91 90)
		(unit 1)
		(exclude_from_sim no)
		(in_bom no)
		(on_board yes)
		(dnp no)
		(property "Reference" "TP1"
			(at 92.075 36.83 90)
			(effects
				(font
					(size 1.27 1.27)
					(thickness 0.15)
				)
				(justify right)
			)
		)
		(property "Value" "TP_0.75mm_SMD"
			(at 97.79 31.75 0)
			(effects
				(font
					(size 1.27 1.27)
					(thickness 0.15)
				)
				(justify left bottom)
				(hide yes)
			)
		)
		(property "Footprint" "antmicro-footprints:TP_SMD_0.75mm"
			(at 100.33 31.75 0)
			(effects
				(font
					(size 1.27 1.27)
					(thickness 0.15)
				)
				(justify left bottom)
				(hide yes)
			)
		)
		(property "Datasheet" ""
			(at 106.68 24.13 0)
			(effects
				(font
					(size 1.27 1.27)
					(thickness 0.15)
				)
				(justify left bottom)
				(hide yes)
			)
		)
		(property "Description" "SMT test point"
			(at 107.95 31.115 0)
			(effects
				(font
					(size 1.27 1.27)
				)
				(justify left bottom)
				(hide yes)
			)
		)
		(property "License" "Apache-2.0"
			(at 105.41 31.75 0)
			(effects
				(font
					(size 1.27 1.27)
					(thickness 0.15)
				)
				(justify left bottom)
				(hide yes)
			)
		)
		(property "Manufacturer" ""
			(at 100.33 31.115 0)
			(effects
				(font
					(size 1.27 1.27)
					(thickness 0.15)
				)
				(justify left bottom)
				(hide yes)
			)
		)
		(property "MPN" ""
			(at 105.41 31.115 0)
			(effects
				(font
					(size 1.27 1.27)
					(thickness 0.15)
				)
				(justify left bottom)
				(hide yes)
			)
		)
		(property "Author" "Antmicro"
			(at 102.87 31.75 0)
			(effects
				(font
					(size 1.27 1.27)
					(thickness 0.15)
				)
				(justify left bottom)
				(hide yes)
			)
		)
		(pin "1"
		)
		(instances
			(project "thunderbolt-to-10gbe-adapter"
				(path ""
					(reference "TP1")
					(unit 1)
				)
			)
		)
	)
	(symbol
		(lib_id "antmicropower:GND")
		(at 252.73 132.08 0)
		(unit 1)
		(exclude_from_sim no)
		(in_bom yes)
		(on_board yes)
		(dnp no)
		(property "Reference" "#PWR037"
			(at 252.73 138.43 0)
			(effects
				(font
					(size 1.27 1.27)
				)
				(hide yes)
			)
		)
		(property "Value" "GND"
			(at 252.73 135.89 0)
			(effects
				(font
					(size 1.27 1.27)
				)
			)
		)
		(property "Footprint" ""
			(at 252.73 132.08 0)
			(effects
				(font
					(size 1.27 1.27)
				)
				(hide yes)
			)
		)
		(property "Datasheet" ""
			(at 252.73 132.08 0)
			(effects
				(font
					(size 1.27 1.27)
				)
				(hide yes)
			)
		)
		(property "Description" ""
			(at 252.73 132.08 0)
			(effects
				(font
					(size 1.27 1.27)
				)
				(hide yes)
			)
		)
		(property "Author" "Antmicro"
			(at 261.62 139.7 0)
			(effects
				(font
					(size 1.27 1.27)
					(thickness 0.15)
				)
				(justify left bottom)
				(hide yes)
			)
		)
		(property "License" "Apache-2.0"
			(at 261.62 142.24 0)
			(effects
				(font
					(size 1.27 1.27)
					(thickness 0.15)
				)
				(justify left bottom)
				(hide yes)
			)
		)
		(pin "1"
		)
		(instances
			(project "thunderbolt-gpu-adapter"
				(path ""
					(reference "#PWR050")
					(unit 1)
				)
			)
			(project "thunderbolt-to-10gbe-adapter"
				(path ""
					(reference "#PWR037")
					(unit 1)
				)
			)
		)
	)
	(symbol
		(lib_id "antmicroCapacitorsmisc:C_22u_25V_0805")
		(at 129.54 50.8 90)
		(unit 1)
		(exclude_from_sim no)
		(in_bom yes)
		(on_board yes)
		(dnp no)
		(property "Reference" "C8"
			(at 131.318 45.7201 90)
			(effects
				(font
					(size 1.27 1.27)
					(thickness 0.15)
				)
				(justify right)
			)
		)
		(property "Value" "C_22u_25V_0805"
			(at 139.7 30.48 0)
			(effects
				(font
					(size 1.27 1.27)
					(thickness 0.15)
				)
				(justify left bottom)
				(hide yes)
			)
		)
		(property "Footprint" "antmicro-footprints:C_0805_2012Metric"
			(at 142.24 30.48 0)
			(effects
				(font
					(size 1.27 1.27)
					(thickness 0.15)
				)
				(justify left bottom)
				(hide yes)
			)
		)
		(property "Datasheet" "https://product.samsungsem.com/mlcc/CL21A226MAYNNN.do"
			(at 144.78 30.48 0)
			(effects
				(font
					(size 1.27 1.27)
					(thickness 0.15)
				)
				(justify left bottom)
				(hide yes)
			)
		)
		(property "Description" "SMT Multilayer Ceramic Capacitor, 22uF, +/-20%, 25V, X5R, 0805 [2012 Metric]"
			(at 162.56 30.48 0)
			(effects
				(font
					(size 1.27 1.27)
				)
				(justify left bottom)
				(hide yes)
			)
		)
		(property "MPN" "CL21A226MAYNNNE"
			(at 147.32 30.48 0)
			(effects
				(font
					(size 1.27 1.27)
					(thickness 0.15)
				)
				(justify left bottom)
				(hide yes)
			)
		)
		(property "Manufacturer" "Samsung Electro-Mechanics"
			(at 149.86 30.48 0)
			(effects
				(font
					(size 1.27 1.27)
					(thickness 0.15)
				)
				(justify left bottom)
				(hide yes)
			)
		)
		(property "License" "Apache-2.0"
			(at 152.4 30.48 0)
			(effects
				(font
					(size 1.27 1.27)
					(thickness 0.15)
				)
				(justify left bottom)
				(hide yes)
			)
		)
		(property "Author" "Antmicro"
			(at 154.94 30.48 0)
			(effects
				(font
					(size 1.27 1.27)
					(thickness 0.15)
				)
				(justify left bottom)
				(hide yes)
			)
		)
		(property "Val" "22u"
			(at 131.318 48.2601 90)
			(effects
				(font
					(size 1.27 1.27)
					(thickness 0.15)
				)
				(justify right)
			)
		)
		(property "Voltage" "25V"
			(at 131.318 50.8 90)
			(effects
				(font
					(size 1.27 1.27)
				)
				(justify right)
			)
		)
		(property "Dielectric" "X5R"
			(at 160.02 30.48 0)
			(effects
				(font
					(size 1.27 1.27)
				)
				(justify left bottom)
				(hide yes)
			)
		)
		(property "Public" "False"
			(at 162.56 30.48 0)
			(effects
				(font
					(size 1.27 1.27)
				)
				(justify left bottom)
				(hide yes)
			)
		)
		(pin "2"
		)
		(pin "1"
		)
		(instances
			(project "thunderbolt-to-10gbe-adapter"
				(path ""
					(reference "C8")
					(unit 1)
				)
			)
		)
	)
	(symbol
		(lib_id "antmicropower:GND")
		(at 252.73 231.14 0)
		(unit 1)
		(exclude_from_sim no)
		(in_bom yes)
		(on_board yes)
		(dnp no)
		(property "Reference" "#PWR045"
			(at 252.73 237.49 0)
			(effects
				(font
					(size 1.27 1.27)
				)
				(hide yes)
			)
		)
		(property "Value" "GND"
			(at 252.73 234.95 0)
			(effects
				(font
					(size 1.27 1.27)
				)
			)
		)
		(property "Footprint" ""
			(at 252.73 231.14 0)
			(effects
				(font
					(size 1.27 1.27)
				)
				(hide yes)
			)
		)
		(property "Datasheet" ""
			(at 252.73 231.14 0)
			(effects
				(font
					(size 1.27 1.27)
				)
				(hide yes)
			)
		)
		(property "Description" ""
			(at 252.73 231.14 0)
			(effects
				(font
					(size 1.27 1.27)
				)
				(hide yes)
			)
		)
		(property "Author" "Antmicro"
			(at 261.62 238.76 0)
			(effects
				(font
					(size 1.27 1.27)
					(thickness 0.15)
				)
				(justify left bottom)
				(hide yes)
			)
		)
		(property "License" "Apache-2.0"
			(at 261.62 241.3 0)
			(effects
				(font
					(size 1.27 1.27)
					(thickness 0.15)
				)
				(justify left bottom)
				(hide yes)
			)
		)
		(pin "1"
		)
		(instances
			(project "thunderbolt-gpu-adapter"
				(path ""
					(reference "#PWR057")
					(unit 1)
				)
			)
			(project "thunderbolt-to-10gbe-adapter"
				(path ""
					(reference "#PWR045")
					(unit 1)
				)
			)
		)
	)
	(symbol
		(lib_id "antmicroResistors0402:R_0R_0402")
		(at 240.03 215.9 0)
		(unit 1)
		(exclude_from_sim no)
		(in_bom yes)
		(on_board yes)
		(dnp no)
		(property "Reference" "R25"
			(at 242.57 213.995 0)
			(effects
				(font
					(size 1.27 1.27)
					(thickness 0.15)
				)
			)
		)
		(property "Value" "R_0R_0402"
			(at 260.35 228.6 0)
			(effects
				(font
					(size 1.27 1.27)
					(thickness 0.15)
				)
				(justify left bottom)
				(hide yes)
			)
		)
		(property "Footprint" "antmicro-footprints:R_0402_1005Metric"
			(at 260.35 231.14 0)
			(effects
				(font
					(size 1.27 1.27)
					(thickness 0.15)
				)
				(justify left bottom)
				(hide yes)
			)
		)
		(property "Datasheet" "https://industrial.panasonic.com/cdbs/www-data/pdf/RDA0000/AOA0000C301.pdf"
			(at 260.35 233.68 0)
			(effects
				(font
					(size 1.27 1.27)
					(thickness 0.15)
				)
				(justify left bottom)
				(hide yes)
			)
		)
		(property "Description" "SMD Chip Resistor, Jumper, 0 ohm, 100 mW, 0402 [1005 Metric], Thick Film, General Purpose"
			(at 240.03 215.9 0)
			(effects
				(font
					(size 1.27 1.27)
				)
				(hide yes)
			)
		)
		(property "MPN" "ERJ2GE0R00X"
			(at 260.35 236.22 0)
			(effects
				(font
					(size 1.27 1.27)
					(thickness 0.15)
				)
				(justify left bottom)
				(hide yes)
			)
		)
		(property "Manufacturer" "Panasonic"
			(at 260.35 238.76 0)
			(effects
				(font
					(size 1.27 1.27)
					(thickness 0.15)
				)
				(justify left bottom)
				(hide yes)
			)
		)
		(property "License" "Apache-2.0"
			(at 260.35 241.3 0)
			(effects
				(font
					(size 1.27 1.27)
					(thickness 0.15)
				)
				(justify left bottom)
				(hide yes)
			)
		)
		(property "Val" "0R"
			(at 242.57 215.9 0)
			(effects
				(font
					(size 1.27 1.27)
					(thickness 0.15)
				)
			)
		)
		(property "Tolerance" "~"
			(at 260.35 226.06 0)
			(effects
				(font
					(size 1.27 1.27)
				)
				(justify left bottom)
				(hide yes)
			)
		)
		(property "Current" "1A"
			(at 242.57 212.725 0)
			(effects
				(font
					(size 1.27 1.27)
					(thickness 0.15)
				)
				(hide yes)
			)
		)
		(property "Author" "Antmicro"
			(at 260.35 243.84 0)
			(effects
				(font
					(size 1.27 1.27)
					(thickness 0.15)
				)
				(justify left bottom)
				(hide yes)
			)
		)
		(pin "1"
		)
		(pin "2"
		)
		(instances
			(project "thunderbolt-gpu-adapter"
				(path ""
					(reference "R31")
					(unit 1)
				)
			)
			(project "thunderbolt-to-10gbe-adapter"
				(path ""
					(reference "R25")
					(unit 1)
				)
			)
		)
	)
	(symbol
		(lib_id "antmicroResistors0402:R_100k_0402")
		(at 240.03 208.28 0)
		(unit 1)
		(exclude_from_sim no)
		(in_bom yes)
		(on_board yes)
		(dnp no)
		(property "Reference" "R23"
			(at 238.125 207.01 0)
			(effects
				(font
					(size 1.27 1.27)
					(thickness 0.15)
				)
			)
		)
		(property "Value" "R_100k_0402"
			(at 260.35 220.98 0)
			(effects
				(font
					(size 1.27 1.27)
					(thickness 0.15)
				)
				(justify left bottom)
				(hide yes)
			)
		)
		(property "Footprint" "antmicro-footprints:R_0402_1005Metric"
			(at 260.35 223.52 0)
			(effects
				(font
					(size 1.27 1.27)
					(thickness 0.15)
				)
				(justify left bottom)
				(hide yes)
			)
		)
		(property "Datasheet" "https://www.bourns.com/docs/product-datasheets/cr.pdf"
			(at 260.35 226.06 0)
			(effects
				(font
					(size 1.27 1.27)
					(thickness 0.15)
				)
				(justify left bottom)
				(hide yes)
			)
		)
		(property "Description" "SMD Chip Resistor, 100 kohm, ± 1%, 62.5 mW, 0402 [1005 Metric], Thick Film, General Purpose"
			(at 240.03 208.28 0)
			(effects
				(font
					(size 1.27 1.27)
				)
				(hide yes)
			)
		)
		(property "MPN" "CR0402-FX-1003GLF"
			(at 260.35 228.6 0)
			(effects
				(font
					(size 1.27 1.27)
					(thickness 0.15)
				)
				(justify left bottom)
				(hide yes)
			)
		)
		(property "Manufacturer" "Bourns"
			(at 260.35 231.14 0)
			(effects
				(font
					(size 1.27 1.27)
					(thickness 0.15)
				)
				(justify left bottom)
				(hide yes)
			)
		)
		(property "License" "Apache-2.0"
			(at 260.35 233.68 0)
			(effects
				(font
					(size 1.27 1.27)
					(thickness 0.15)
				)
				(justify left bottom)
				(hide yes)
			)
		)
		(property "Val" "100k"
			(at 247.015 207.01 0)
			(effects
				(font
					(size 1.27 1.27)
					(thickness 0.15)
				)
			)
		)
		(property "Tolerance" "1%"
			(at 260.35 218.44 0)
			(effects
				(font
					(size 1.27 1.27)
				)
				(justify left bottom)
				(hide yes)
			)
		)
		(property "Author" "Antmicro"
			(at 260.35 236.22 0)
			(effects
				(font
					(size 1.27 1.27)
					(thickness 0.15)
				)
				(justify left bottom)
				(hide yes)
			)
		)
		(pin "1"
		)
		(pin "2"
		)
		(instances
			(project "thunderbolt-gpu-adapter"
				(path ""
					(reference "R29")
					(unit 1)
				)
			)
			(project "thunderbolt-to-10gbe-adapter"
				(path ""
					(reference "R23")
					(unit 1)
				)
			)
		)
	)
	(symbol
		(lib_id "antmicroCapacitors0402:C_2u2_0402")
		(at 237.49 147.32 0)
		(unit 1)
		(exclude_from_sim no)
		(in_bom yes)
		(on_board yes)
		(dnp no)
		(property "Reference" "C21"
			(at 242.57 146.05 0)
			(effects
				(font
					(size 1.27 1.27)
					(thickness 0.15)
				)
			)
		)
		(property "Value" "C_2u2_0402"
			(at 257.81 157.48 0)
			(effects
				(font
					(size 1.27 1.27)
					(thickness 0.15)
				)
				(justify left bottom)
				(hide yes)
			)
		)
		(property "Footprint" "antmicro-footprints:C_0402_1005Metric"
			(at 257.81 160.02 0)
			(effects
				(font
					(size 1.27 1.27)
					(thickness 0.15)
				)
				(justify left bottom)
				(hide yes)
			)
		)
		(property "Datasheet" "https://product.tdk.com/en/search/capacitor/ceramic/mlcc/info?part_no=C1005X5R1A225K050BC"
			(at 257.81 162.56 0)
			(effects
				(font
					(size 1.27 1.27)
					(thickness 0.15)
				)
				(justify left bottom)
				(hide yes)
			)
		)
		(property "Description" "SMD Multilayer Ceramic Capacitor, 2.2 µF, 10 V, 0402 [1005 Metric], ± 10%, X5R, C"
			(at 237.49 147.32 0)
			(effects
				(font
					(size 1.27 1.27)
				)
				(hide yes)
			)
		)
		(property "MPN" "C1005X5R1A225K050BC"
			(at 257.81 165.1 0)
			(effects
				(font
					(size 1.27 1.27)
					(thickness 0.15)
				)
				(justify left bottom)
				(hide yes)
			)
		)
		(property "Manufacturer" "TDK"
			(at 257.81 167.64 0)
			(effects
				(font
					(size 1.27 1.27)
					(thickness 0.15)
				)
				(justify left bottom)
				(hide yes)
			)
		)
		(property "License" "Apache-2.0"
			(at 257.81 170.18 0)
			(effects
				(font
					(size 1.27 1.27)
					(thickness 0.15)
				)
				(justify left bottom)
				(hide yes)
			)
		)
		(property "Val" "2u2"
			(at 242.57 148.59 0)
			(effects
				(font
					(size 1.27 1.27)
					(thickness 0.15)
				)
			)
		)
		(property "Voltage" ""
			(at 257.81 175.26 0)
			(effects
				(font
					(size 1.27 1.27)
				)
				(justify left bottom)
				(hide yes)
			)
		)
		(property "Dielectric" ""
			(at 257.81 177.8 0)
			(effects
				(font
					(size 1.27 1.27)
				)
				(justify left bottom)
				(hide yes)
			)
		)
		(property "Author" "Antmicro"
			(at 257.81 172.72 0)
			(effects
				(font
					(size 1.27 1.27)
					(thickness 0.15)
				)
				(justify left bottom)
				(hide yes)
			)
		)
		(pin "1"
		)
		(pin "2"
		)
		(instances
			(project "thunderbolt-gpu-adapter"
				(path ""
					(reference "C36")
					(unit 1)
				)
			)
			(project "thunderbolt-to-10gbe-adapter"
				(path ""
					(reference "C21")
					(unit 1)
				)
			)
		)
	)
	(symbol
		(lib_id "antmicropower:GND")
		(at 176.53 254 0)
		(unit 1)
		(exclude_from_sim no)
		(in_bom yes)
		(on_board yes)
		(dnp no)
		(property "Reference" "#PWR030"
			(at 176.53 260.35 0)
			(effects
				(font
					(size 1.27 1.27)
				)
				(hide yes)
			)
		)
		(property "Value" "GND"
			(at 176.53 257.81 0)
			(effects
				(font
					(size 1.27 1.27)
				)
			)
		)
		(property "Footprint" ""
			(at 176.53 254 0)
			(effects
				(font
					(size 1.27 1.27)
				)
				(hide yes)
			)
		)
		(property "Datasheet" ""
			(at 176.53 254 0)
			(effects
				(font
					(size 1.27 1.27)
				)
				(hide yes)
			)
		)
		(property "Description" ""
			(at 176.53 254 0)
			(effects
				(font
					(size 1.27 1.27)
				)
				(hide yes)
			)
		)
		(property "Author" "Antmicro"
			(at 185.42 261.62 0)
			(effects
				(font
					(size 1.27 1.27)
					(thickness 0.15)
				)
				(justify left bottom)
				(hide yes)
			)
		)
		(property "License" "Apache-2.0"
			(at 185.42 264.16 0)
			(effects
				(font
					(size 1.27 1.27)
					(thickness 0.15)
				)
				(justify left bottom)
				(hide yes)
			)
		)
		(pin "1"
		)
		(instances
			(project "thunderbolt-gpu-adapter"
				(path ""
					(reference "#PWR040")
					(unit 1)
				)
			)
			(project "thunderbolt-to-10gbe-adapter"
				(path ""
					(reference "#PWR030")
					(unit 1)
				)
			)
		)
	)
	(symbol
		(lib_id "antmicroCapacitors0603:C_22u_0603")
		(at 240.03 71.12 90)
		(unit 1)
		(exclude_from_sim no)
		(in_bom yes)
		(on_board yes)
		(dnp no)
		(fields_autoplaced yes)
		(property "Reference" "C24"
			(at 242.57 67.3036 90)
			(effects
				(font
					(size 1.27 1.27)
					(thickness 0.15)
				)
				(justify right)
			)
		)
		(property "Value" "C_22u_0603"
			(at 250.19 50.8 0)
			(effects
				(font
					(size 1.27 1.27)
					(thickness 0.15)
				)
				(justify left bottom)
				(hide yes)
			)
		)
		(property "Footprint" "antmicro-footprints:C_0603_1608Metric"
			(at 252.73 50.8 0)
			(effects
				(font
					(size 1.27 1.27)
					(thickness 0.15)
				)
				(justify left bottom)
				(hide yes)
			)
		)
		(property "Datasheet" "https://www.murata.com/products/productdetail?partno=GRM188R60J226MEA0%23"
			(at 255.27 50.8 0)
			(effects
				(font
					(size 1.27 1.27)
					(thickness 0.15)
				)
				(justify left bottom)
				(hide yes)
			)
		)
		(property "Description" "SMD Multilayer Ceramic Capacitor, 22 µF, 6.3 V, 0603 [1608 Metric], ± 20%, X5R, GRM Series"
			(at 240.03 71.12 0)
			(effects
				(font
					(size 1.27 1.27)
				)
				(hide yes)
			)
		)
		(property "MPN" "GRM188R60J226MEA0D"
			(at 257.81 50.8 0)
			(effects
				(font
					(size 1.27 1.27)
					(thickness 0.15)
				)
				(justify left bottom)
				(hide yes)
			)
		)
		(property "Manufacturer" "Murata"
			(at 260.35 50.8 0)
			(effects
				(font
					(size 1.27 1.27)
					(thickness 0.15)
				)
				(justify left bottom)
				(hide yes)
			)
		)
		(property "License" "Apache-2.0"
			(at 262.89 50.8 0)
			(effects
				(font
					(size 1.27 1.27)
					(thickness 0.15)
				)
				(justify left bottom)
				(hide yes)
			)
		)
		(property "Val" "22u"
			(at 242.57 69.8436 90)
			(effects
				(font
					(size 1.27 1.27)
					(thickness 0.15)
				)
				(justify right)
			)
		)
		(property "Voltage" ""
			(at 267.97 50.8 0)
			(effects
				(font
					(size 1.27 1.27)
				)
				(justify left bottom)
				(hide yes)
			)
		)
		(property "Dielectric" ""
			(at 270.51 50.8 0)
			(effects
				(font
					(size 1.27 1.27)
				)
				(justify left bottom)
				(hide yes)
			)
		)
		(property "Author" "Antmicro"
			(at 265.43 50.8 0)
			(effects
				(font
					(size 1.27 1.27)
					(thickness 0.15)
				)
				(justify left bottom)
				(hide yes)
			)
		)
		(pin "1"
		)
		(pin "2"
		)
		(instances
			(project "thunderbolt-to-10gbe-adapter"
				(path ""
					(reference "C24")
					(unit 1)
				)
			)
		)
	)
	(symbol
		(lib_id "antmicroCapacitors0402:C_1u_0402")
		(at 168.91 144.78 0)
		(unit 1)
		(exclude_from_sim no)
		(in_bom yes)
		(on_board yes)
		(dnp no)
		(property "Reference" "C14"
			(at 168.91 146.05 0)
			(effects
				(font
					(size 1.27 1.27)
					(thickness 0.15)
				)
			)
		)
		(property "Value" "C_1u_0402"
			(at 189.23 154.94 0)
			(effects
				(font
					(size 1.27 1.27)
					(thickness 0.15)
				)
				(justify left bottom)
				(hide yes)
			)
		)
		(property "Footprint" "antmicro-footprints:C_0402_1005Metric"
			(at 189.23 157.48 0)
			(effects
				(font
					(size 1.27 1.27)
					(thickness 0.15)
				)
				(justify left bottom)
				(hide yes)
			)
		)
		(property "Datasheet" "https://product.tdk.com/en/search/capacitor/ceramic/mlcc/info?part_no=C1005X6S1A105K050BC"
			(at 189.23 160.02 0)
			(effects
				(font
					(size 1.27 1.27)
					(thickness 0.15)
				)
				(justify left bottom)
				(hide yes)
			)
		)
		(property "Description" "SMD Multilayer Ceramic Capacitor, 1 µF, 10 V, 0402 [1005 Metric], ± 10%, X6S, C"
			(at 168.91 144.78 0)
			(effects
				(font
					(size 1.27 1.27)
				)
				(hide yes)
			)
		)
		(property "MPN" "C1005X6S1A105K050BC"
			(at 189.23 162.56 0)
			(effects
				(font
					(size 1.27 1.27)
					(thickness 0.15)
				)
				(justify left bottom)
				(hide yes)
			)
		)
		(property "Manufacturer" "TDK"
			(at 189.23 165.1 0)
			(effects
				(font
					(size 1.27 1.27)
					(thickness 0.15)
				)
				(justify left bottom)
				(hide yes)
			)
		)
		(property "License" "Apache-2.0"
			(at 189.23 167.64 0)
			(effects
				(font
					(size 1.27 1.27)
					(thickness 0.15)
				)
				(justify left bottom)
				(hide yes)
			)
		)
		(property "Val" "1u"
			(at 173.355 146.05 0)
			(effects
				(font
					(size 1.27 1.27)
					(thickness 0.15)
				)
			)
		)
		(property "Voltage" ""
			(at 189.23 172.72 0)
			(effects
				(font
					(size 1.27 1.27)
				)
				(justify left bottom)
				(hide yes)
			)
		)
		(property "Dielectric" ""
			(at 189.23 175.26 0)
			(effects
				(font
					(size 1.27 1.27)
				)
				(justify left bottom)
				(hide yes)
			)
		)
		(property "Author" "Antmicro"
			(at 189.23 170.18 0)
			(effects
				(font
					(size 1.27 1.27)
					(thickness 0.15)
				)
				(justify left bottom)
				(hide yes)
			)
		)
		(pin "1"
		)
		(pin "2"
		)
		(instances
			(project "thunderbolt-to-10gbe-adapter"
				(path ""
					(reference "C14")
					(unit 1)
				)
			)
		)
	)
	(symbol
		(lib_id "antmicroResistors0402:R_40k2_0402")
		(at 214.63 66.04 90)
		(unit 1)
		(exclude_from_sim no)
		(in_bom yes)
		(on_board yes)
		(dnp no)
		(fields_autoplaced yes)
		(property "Reference" "R21"
			(at 217.17 62.23 90)
			(effects
				(font
					(size 1.27 1.27)
					(thickness 0.15)
				)
				(justify right)
			)
		)
		(property "Value" "R_40k2_0402"
			(at 227.33 45.72 0)
			(effects
				(font
					(size 1.27 1.27)
					(thickness 0.15)
				)
				(justify left bottom)
				(hide yes)
			)
		)
		(property "Footprint" "antmicro-footprints:R_0402_1005Metric"
			(at 229.87 45.72 0)
			(effects
				(font
					(size 1.27 1.27)
					(thickness 0.15)
				)
				(justify left bottom)
				(hide yes)
			)
		)
		(property "Datasheet" "https://www.bourns.com/docs/product-datasheets/cr.pdf"
			(at 232.41 45.72 0)
			(effects
				(font
					(size 1.27 1.27)
					(thickness 0.15)
				)
				(justify left bottom)
				(hide yes)
			)
		)
		(property "Description" "SMD Chip Resistor, 40.2 kohm, ± 1%, 63 mW, 0402 [1005 Metric], Thick Film, General Purpose"
			(at 214.63 66.04 0)
			(effects
				(font
					(size 1.27 1.27)
				)
				(hide yes)
			)
		)
		(property "MPN" "CR0402-FX-4022GLF"
			(at 234.95 45.72 0)
			(effects
				(font
					(size 1.27 1.27)
					(thickness 0.15)
				)
				(justify left bottom)
				(hide yes)
			)
		)
		(property "Manufacturer" "Bourns"
			(at 237.49 45.72 0)
			(effects
				(font
					(size 1.27 1.27)
					(thickness 0.15)
				)
				(justify left bottom)
				(hide yes)
			)
		)
		(property "License" "Apache-2.0"
			(at 240.03 45.72 0)
			(effects
				(font
					(size 1.27 1.27)
					(thickness 0.15)
				)
				(justify left bottom)
				(hide yes)
			)
		)
		(property "Val" "40k2"
			(at 217.17 64.77 90)
			(effects
				(font
					(size 1.27 1.27)
					(thickness 0.15)
				)
				(justify right)
			)
		)
		(property "Tolerance" "1%"
			(at 224.79 45.72 0)
			(effects
				(font
					(size 1.27 1.27)
				)
				(justify left bottom)
				(hide yes)
			)
		)
		(property "Author" "Antmicro"
			(at 242.57 45.72 0)
			(effects
				(font
					(size 1.27 1.27)
					(thickness 0.15)
				)
				(justify left bottom)
				(hide yes)
			)
		)
		(pin "1"
		)
		(pin "2"
		)
		(instances
			(project "thunderbolt-to-10gbe-adapter"
				(path ""
					(reference "R21")
					(unit 1)
				)
			)
		)
	)
	(symbol
		(lib_id "antmicropower:PWR_FLAG")
		(at 267.97 127 0)
		(unit 1)
		(exclude_from_sim no)
		(in_bom yes)
		(on_board yes)
		(dnp no)
		(fields_autoplaced yes)
		(property "Reference" "#FLG07"
			(at 267.97 125.095 0)
			(effects
				(font
					(size 1.27 1.27)
				)
				(hide yes)
			)
		)
		(property "Value" "PWR_FLAG"
			(at 267.97 121.92 0)
			(effects
				(font
					(size 1.27 1.27)
				)
			)
		)
		(property "Footprint" ""
			(at 267.97 127 0)
			(effects
				(font
					(size 1.27 1.27)
				)
				(hide yes)
			)
		)
		(property "Datasheet" ""
			(at 267.97 127 0)
			(effects
				(font
					(size 1.27 1.27)
				)
				(hide yes)
			)
		)
		(property "Description" ""
			(at 267.97 127 0)
			(effects
				(font
					(size 1.27 1.27)
				)
				(hide yes)
			)
		)
		(pin "1"
		)
		(instances
			(project "thunderbolt-gpu-adapter"
				(path ""
					(reference "#FLG0107")
					(unit 1)
				)
			)
			(project "thunderbolt-to-10gbe-adapter"
				(path ""
					(reference "#FLG07")
					(unit 1)
				)
			)
		)
	)
	(symbol
		(lib_id "antmicropower:GND")
		(at 257.81 77.47 0)
		(unit 1)
		(exclude_from_sim no)
		(in_bom yes)
		(on_board yes)
		(dnp no)
		(fields_autoplaced yes)
		(property "Reference" "#PWR047"
			(at 257.81 83.82 0)
			(effects
				(font
					(size 1.27 1.27)
				)
				(hide yes)
			)
		)
		(property "Value" "GND"
			(at 257.81 81.28 0)
			(effects
				(font
					(size 1.27 1.27)
				)
			)
		)
		(property "Footprint" ""
			(at 257.81 77.47 0)
			(effects
				(font
					(size 1.27 1.27)
				)
				(hide yes)
			)
		)
		(property "Datasheet" ""
			(at 257.81 77.47 0)
			(effects
				(font
					(size 1.27 1.27)
				)
				(hide yes)
			)
		)
		(property "Description" ""
			(at 257.81 77.47 0)
			(effects
				(font
					(size 1.27 1.27)
				)
				(hide yes)
			)
		)
		(property "Author" "Antmicro"
			(at 266.7 85.09 0)
			(effects
				(font
					(size 1.27 1.27)
					(thickness 0.15)
				)
				(justify left bottom)
				(hide yes)
			)
		)
		(property "License" "Apache-2.0"
			(at 266.7 87.63 0)
			(effects
				(font
					(size 1.27 1.27)
					(thickness 0.15)
				)
				(justify left bottom)
				(hide yes)
			)
		)
		(pin "1"
		)
		(instances
			(project "thunderbolt-to-10gbe-adapter"
				(path ""
					(reference "#PWR047")
					(unit 1)
				)
			)
		)
	)
	(symbol
		(lib_id "antmicropower:GND")
		(at 153.67 76.2 0)
		(unit 1)
		(exclude_from_sim no)
		(in_bom yes)
		(on_board yes)
		(dnp no)
		(property "Reference" "#PWR026"
			(at 153.67 82.55 0)
			(effects
				(font
					(size 1.27 1.27)
				)
				(hide yes)
			)
		)
		(property "Value" "GND"
			(at 153.67 80.01 0)
			(effects
				(font
					(size 1.27 1.27)
				)
			)
		)
		(property "Footprint" ""
			(at 153.67 76.2 0)
			(effects
				(font
					(size 1.27 1.27)
				)
				(hide yes)
			)
		)
		(property "Datasheet" ""
			(at 153.67 76.2 0)
			(effects
				(font
					(size 1.27 1.27)
				)
				(hide yes)
			)
		)
		(property "Description" ""
			(at 153.67 76.2 0)
			(effects
				(font
					(size 1.27 1.27)
				)
				(hide yes)
			)
		)
		(property "Author" "Antmicro"
			(at 162.56 83.82 0)
			(effects
				(font
					(size 1.27 1.27)
					(thickness 0.15)
				)
				(justify left bottom)
				(hide yes)
			)
		)
		(property "License" "Apache-2.0"
			(at 162.56 86.36 0)
			(effects
				(font
					(size 1.27 1.27)
					(thickness 0.15)
				)
				(justify left bottom)
				(hide yes)
			)
		)
		(pin "1"
		)
		(instances
			(project "thunderbolt-to-10gbe-adapter"
				(path ""
					(reference "#PWR026")
					(unit 1)
				)
			)
		)
	)
	(symbol
		(lib_id "antmicroResistors0603:R_0R_22.4A_0603")
		(at 100.33 43.18 0)
		(unit 1)
		(exclude_from_sim no)
		(in_bom yes)
		(on_board yes)
		(dnp no)
		(property "Reference" "R3"
			(at 102.87 38.1 0)
			(effects
				(font
					(size 1.27 1.27)
					(thickness 0.15)
				)
			)
		)
		(property "Value" "R_0R_22.4A_0603"
			(at 115.57 48.26 0)
			(effects
				(font
					(size 1.27 1.27)
					(thickness 0.15)
				)
				(justify left bottom)
				(hide yes)
			)
		)
		(property "Footprint" "antmicro-footprints:R_0603_1608Metric"
			(at 115.57 53.34 0)
			(effects
				(font
					(size 1.27 1.27)
					(thickness 0.15)
				)
				(justify left bottom)
				(hide yes)
			)
		)
		(property "Datasheet" "https://fscdn.rohm.com/en/products/databook/datasheet/passive/resistor/chip_resistor/pmr-jpw-e.pdf"
			(at 115.57 55.88 0)
			(effects
				(font
					(size 1.27 1.27)
					(thickness 0.15)
				)
				(justify left bottom)
				(hide yes)
			)
		)
		(property "Description" "SMD Chip Resistor"
			(at 115.57 71.12 0)
			(effects
				(font
					(size 1.27 1.27)
				)
				(justify left bottom)
				(hide yes)
			)
		)
		(property "MPN" "PMR03EZPJ000"
			(at 115.57 58.42 0)
			(effects
				(font
					(size 1.27 1.27)
					(thickness 0.15)
				)
				(justify left bottom)
				(hide yes)
			)
		)
		(property "Manufacturer" "ROHM Semiconductor"
			(at 115.57 60.96 0)
			(effects
				(font
					(size 1.27 1.27)
					(thickness 0.15)
				)
				(justify left bottom)
				(hide yes)
			)
		)
		(property "Val" "0R"
			(at 102.87 40.64 0)
			(effects
				(font
					(size 1.27 1.27)
					(thickness 0.15)
				)
			)
		)
		(property "Max. Curr." "22.4A"
			(at 102.87 45.72 0)
			(effects
				(font
					(size 1.27 1.27)
					(thickness 0.15)
				)
			)
		)
		(property "Author" "Antmicro"
			(at 115.57 66.04 0)
			(effects
				(font
					(size 1.27 1.27)
					(thickness 0.15)
				)
				(justify left bottom)
				(hide yes)
			)
		)
		(property "License" "Apache-2.0"
			(at 115.57 68.58 0)
			(effects
				(font
					(size 1.27 1.27)
					(thickness 0.15)
				)
				(justify left bottom)
				(hide yes)
			)
		)
		(property "Tolerance" "template_tolerance"
			(at 120.65 53.34 0)
			(effects
				(font
					(size 1.27 1.27)
				)
				(justify left bottom)
				(hide yes)
			)
		)
		(pin "1"
		)
		(pin "2"
		)
		(instances
			(project "thunderbolt-to-10gbe-adapter"
				(path ""
					(reference "R3")
					(unit 1)
				)
			)
		)
	)
	(symbol
		(lib_id "antmicroCapacitors0603:C_22u_0603")
		(at 257.81 71.12 90)
		(unit 1)
		(exclude_from_sim no)
		(in_bom yes)
		(on_board yes)
		(dnp no)
		(fields_autoplaced yes)
		(property "Reference" "C27"
			(at 260.35 67.3036 90)
			(effects
				(font
					(size 1.27 1.27)
					(thickness 0.15)
				)
				(justify right)
			)
		)
		(property "Value" "C_22u_0603"
			(at 267.97 50.8 0)
			(effects
				(font
					(size 1.27 1.27)
					(thickness 0.15)
				)
				(justify left bottom)
				(hide yes)
			)
		)
		(property "Footprint" "antmicro-footprints:C_0603_1608Metric"
			(at 270.51 50.8 0)
			(effects
				(font
					(size 1.27 1.27)
					(thickness 0.15)
				)
				(justify left bottom)
				(hide yes)
			)
		)
		(property "Datasheet" "https://www.murata.com/products/productdetail?partno=GRM188R60J226MEA0%23"
			(at 273.05 50.8 0)
			(effects
				(font
					(size 1.27 1.27)
					(thickness 0.15)
				)
				(justify left bottom)
				(hide yes)
			)
		)
		(property "Description" "SMD Multilayer Ceramic Capacitor, 22 µF, 6.3 V, 0603 [1608 Metric], ± 20%, X5R, GRM Series"
			(at 257.81 71.12 0)
			(effects
				(font
					(size 1.27 1.27)
				)
				(hide yes)
			)
		)
		(property "MPN" "GRM188R60J226MEA0D"
			(at 275.59 50.8 0)
			(effects
				(font
					(size 1.27 1.27)
					(thickness 0.15)
				)
				(justify left bottom)
				(hide yes)
			)
		)
		(property "Manufacturer" "Murata"
			(at 278.13 50.8 0)
			(effects
				(font
					(size 1.27 1.27)
					(thickness 0.15)
				)
				(justify left bottom)
				(hide yes)
			)
		)
		(property "License" "Apache-2.0"
			(at 280.67 50.8 0)
			(effects
				(font
					(size 1.27 1.27)
					(thickness 0.15)
				)
				(justify left bottom)
				(hide yes)
			)
		)
		(property "Val" "22u"
			(at 260.35 69.8436 90)
			(effects
				(font
					(size 1.27 1.27)
					(thickness 0.15)
				)
				(justify right)
			)
		)
		(property "Voltage" ""
			(at 285.75 50.8 0)
			(effects
				(font
					(size 1.27 1.27)
				)
				(justify left bottom)
				(hide yes)
			)
		)
		(property "Dielectric" ""
			(at 288.29 50.8 0)
			(effects
				(font
					(size 1.27 1.27)
				)
				(justify left bottom)
				(hide yes)
			)
		)
		(property "Author" "Antmicro"
			(at 283.21 50.8 0)
			(effects
				(font
					(size 1.27 1.27)
					(thickness 0.15)
				)
				(justify left bottom)
				(hide yes)
			)
		)
		(pin "1"
		)
		(pin "2"
		)
		(instances
			(project "thunderbolt-to-10gbe-adapter"
				(path ""
					(reference "C27")
					(unit 1)
				)
			)
		)
	)
	(symbol
		(lib_id "antmicroResistors0402:R_10k_0402")
		(at 168.91 190.5 0)
		(unit 1)
		(exclude_from_sim no)
		(in_bom yes)
		(on_board yes)
		(dnp no)
		(property "Reference" "R17"
			(at 171.45 188.595 0)
			(effects
				(font
					(size 1.27 1.27)
					(thickness 0.15)
				)
			)
		)
		(property "Value" "R_10k_0402"
			(at 189.23 203.2 0)
			(effects
				(font
					(size 1.27 1.27)
					(thickness 0.15)
				)
				(justify left bottom)
				(hide yes)
			)
		)
		(property "Footprint" "antmicro-footprints:R_0402_1005Metric"
			(at 189.23 205.74 0)
			(effects
				(font
					(size 1.27 1.27)
					(thickness 0.15)
				)
				(justify left bottom)
				(hide yes)
			)
		)
		(property "Datasheet" "https://www.bourns.com/docs/product-datasheets/cr.pdf"
			(at 189.23 208.28 0)
			(effects
				(font
					(size 1.27 1.27)
					(thickness 0.15)
				)
				(justify left bottom)
				(hide yes)
			)
		)
		(property "Description" "SMD Chip Resistor, 10 kohm, ± 1%, 62.5 mW, 0402 [1005 Metric], Thick Film, General Purpose"
			(at 168.91 190.5 0)
			(effects
				(font
					(size 1.27 1.27)
				)
				(hide yes)
			)
		)
		(property "MPN" "CR0402-FX-1002GLF"
			(at 189.23 210.82 0)
			(effects
				(font
					(size 1.27 1.27)
					(thickness 0.15)
				)
				(justify left bottom)
				(hide yes)
			)
		)
		(property "Manufacturer" "Bourns"
			(at 189.23 213.36 0)
			(effects
				(font
					(size 1.27 1.27)
					(thickness 0.15)
				)
				(justify left bottom)
				(hide yes)
			)
		)
		(property "License" "Apache-2.0"
			(at 189.23 215.9 0)
			(effects
				(font
					(size 1.27 1.27)
					(thickness 0.15)
				)
				(justify left bottom)
				(hide yes)
			)
		)
		(property "Val" "10k"
			(at 171.45 190.5 0)
			(effects
				(font
					(size 1.27 1.27)
					(thickness 0.15)
				)
			)
		)
		(property "Tolerance" "1%"
			(at 189.23 200.66 0)
			(effects
				(font
					(size 1.27 1.27)
				)
				(justify left bottom)
				(hide yes)
			)
		)
		(property "Author" "Antmicro"
			(at 189.23 218.44 0)
			(effects
				(font
					(size 1.27 1.27)
					(thickness 0.15)
				)
				(justify left bottom)
				(hide yes)
			)
		)
		(pin "1"
		)
		(pin "2"
		)
		(instances
			(project "thunderbolt-gpu-adapter"
				(path ""
					(reference "R19")
					(unit 1)
				)
			)
			(project "thunderbolt-to-10gbe-adapter"
				(path ""
					(reference "R17")
					(unit 1)
				)
			)
		)
	)
	(symbol
		(lib_id "antmicropower:GND")
		(at 266.7 167.64 0)
		(unit 1)
		(exclude_from_sim no)
		(in_bom yes)
		(on_board yes)
		(dnp no)
		(property "Reference" "#PWR051"
			(at 266.7 173.99 0)
			(effects
				(font
					(size 1.27 1.27)
				)
				(hide yes)
			)
		)
		(property "Value" "GND"
			(at 266.7 171.45 0)
			(effects
				(font
					(size 1.27 1.27)
				)
			)
		)
		(property "Footprint" ""
			(at 266.7 167.64 0)
			(effects
				(font
					(size 1.27 1.27)
				)
				(hide yes)
			)
		)
		(property "Datasheet" ""
			(at 266.7 167.64 0)
			(effects
				(font
					(size 1.27 1.27)
				)
				(hide yes)
			)
		)
		(property "Description" ""
			(at 266.7 167.64 0)
			(effects
				(font
					(size 1.27 1.27)
				)
				(hide yes)
			)
		)
		(property "Author" "Antmicro"
			(at 275.59 175.26 0)
			(effects
				(font
					(size 1.27 1.27)
					(thickness 0.15)
				)
				(justify left bottom)
				(hide yes)
			)
		)
		(property "License" "Apache-2.0"
			(at 275.59 177.8 0)
			(effects
				(font
					(size 1.27 1.27)
					(thickness 0.15)
				)
				(justify left bottom)
				(hide yes)
			)
		)
		(pin "1"
		)
		(instances
			(project "thunderbolt-gpu-adapter"
				(path ""
					(reference "#PWR066")
					(unit 1)
				)
			)
			(project "thunderbolt-to-10gbe-adapter"
				(path ""
					(reference "#PWR051")
					(unit 1)
				)
			)
		)
	)
	(symbol
		(lib_id "antmicroResistors0402:R_10k_0402")
		(at 240.03 226.06 0)
		(unit 1)
		(exclude_from_sim no)
		(in_bom yes)
		(on_board yes)
		(dnp no)
		(property "Reference" "R26"
			(at 238.125 224.79 0)
			(effects
				(font
					(size 1.27 1.27)
					(thickness 0.15)
				)
			)
		)
		(property "Value" "R_10k_0402"
			(at 260.35 238.76 0)
			(effects
				(font
					(size 1.27 1.27)
					(thickness 0.15)
				)
				(justify left bottom)
				(hide yes)
			)
		)
		(property "Footprint" "antmicro-footprints:R_0402_1005Metric"
			(at 260.35 241.3 0)
			(effects
				(font
					(size 1.27 1.27)
					(thickness 0.15)
				)
				(justify left bottom)
				(hide yes)
			)
		)
		(property "Datasheet" "https://www.bourns.com/docs/product-datasheets/cr.pdf"
			(at 260.35 243.84 0)
			(effects
				(font
					(size 1.27 1.27)
					(thickness 0.15)
				)
				(justify left bottom)
				(hide yes)
			)
		)
		(property "Description" "SMD Chip Resistor, 10 kohm, ± 1%, 62.5 mW, 0402 [1005 Metric], Thick Film, General Purpose"
			(at 240.03 226.06 0)
			(effects
				(font
					(size 1.27 1.27)
				)
				(hide yes)
			)
		)
		(property "MPN" "CR0402-FX-1002GLF"
			(at 260.35 246.38 0)
			(effects
				(font
					(size 1.27 1.27)
					(thickness 0.15)
				)
				(justify left bottom)
				(hide yes)
			)
		)
		(property "Manufacturer" "Bourns"
			(at 260.35 248.92 0)
			(effects
				(font
					(size 1.27 1.27)
					(thickness 0.15)
				)
				(justify left bottom)
				(hide yes)
			)
		)
		(property "License" "Apache-2.0"
			(at 260.35 251.46 0)
			(effects
				(font
					(size 1.27 1.27)
					(thickness 0.15)
				)
				(justify left bottom)
				(hide yes)
			)
		)
		(property "Val" "10k"
			(at 247.015 224.79 0)
			(effects
				(font
					(size 1.27 1.27)
					(thickness 0.15)
				)
			)
		)
		(property "Tolerance" "1%"
			(at 260.35 236.22 0)
			(effects
				(font
					(size 1.27 1.27)
				)
				(justify left bottom)
				(hide yes)
			)
		)
		(property "Author" "Antmicro"
			(at 260.35 254 0)
			(effects
				(font
					(size 1.27 1.27)
					(thickness 0.15)
				)
				(justify left bottom)
				(hide yes)
			)
		)
		(pin "1"
		)
		(pin "2"
		)
		(instances
			(project "thunderbolt-gpu-adapter"
				(path ""
					(reference "R32")
					(unit 1)
				)
			)
			(project "thunderbolt-to-10gbe-adapter"
				(path ""
					(reference "R26")
					(unit 1)
				)
			)
		)
	)
	(symbol
		(lib_id "antmicropower:GND")
		(at 252.73 142.24 0)
		(unit 1)
		(exclude_from_sim no)
		(in_bom yes)
		(on_board yes)
		(dnp no)
		(property "Reference" "#PWR039"
			(at 252.73 148.59 0)
			(effects
				(font
					(size 1.27 1.27)
				)
				(hide yes)
			)
		)
		(property "Value" "GND"
			(at 252.73 146.05 0)
			(effects
				(font
					(size 1.27 1.27)
				)
			)
		)
		(property "Footprint" ""
			(at 252.73 142.24 0)
			(effects
				(font
					(size 1.27 1.27)
				)
				(hide yes)
			)
		)
		(property "Datasheet" ""
			(at 252.73 142.24 0)
			(effects
				(font
					(size 1.27 1.27)
				)
				(hide yes)
			)
		)
		(property "Description" ""
			(at 252.73 142.24 0)
			(effects
				(font
					(size 1.27 1.27)
				)
				(hide yes)
			)
		)
		(property "Author" "Antmicro"
			(at 261.62 149.86 0)
			(effects
				(font
					(size 1.27 1.27)
					(thickness 0.15)
				)
				(justify left bottom)
				(hide yes)
			)
		)
		(property "License" "Apache-2.0"
			(at 261.62 152.4 0)
			(effects
				(font
					(size 1.27 1.27)
					(thickness 0.15)
				)
				(justify left bottom)
				(hide yes)
			)
		)
		(pin "1"
		)
		(instances
			(project "thunderbolt-gpu-adapter"
				(path ""
					(reference "#PWR051")
					(unit 1)
				)
			)
			(project "thunderbolt-to-10gbe-adapter"
				(path ""
					(reference "#PWR039")
					(unit 1)
				)
			)
		)
	)
	(symbol
		(lib_id "antmicroInterfaceControllers:TPS65983BAZBHR")
		(at 177.8 124.46 0)
		(unit 1)
		(exclude_from_sim no)
		(in_bom yes)
		(on_board yes)
		(dnp no)
		(fields_autoplaced yes)
		(property "Reference" "U3"
			(at 207.01 114.3 0)
			(effects
				(font
					(size 1.27 1.27)
					(thickness 0.15)
				)
			)
		)
		(property "Value" "TPS65983BAZBHR"
			(at 251.46 124.46 0)
			(effects
				(font
					(size 1.27 1.27)
					(thickness 0.15)
				)
				(justify left bottom)
				(hide yes)
			)
		)
		(property "Footprint" "antmicro-footprints:IC_TPS65983BAZBHR"
			(at 251.46 127 0)
			(effects
				(font
					(size 1.27 1.27)
					(thickness 0.15)
				)
				(justify left bottom)
				(hide yes)
			)
		)
		(property "Datasheet" "https://www.ti.com/lit/ds/symlink/tps65983b.pdf?ts=1678712702533&ref_url=https%253A%252F%252Fwww.ti.com%252Fproduct%252FTPS65983B"
			(at 251.46 129.54 0)
			(effects
				(font
					(size 1.27 1.27)
					(thickness 0.15)
				)
				(justify left bottom)
				(hide yes)
			)
		)
		(property "Description" "USB Interface IC Universal USB Type-C and Power Delivery (PD) 3.0 controller 96-NFBGA -10°C to 85"
			(at 177.8 124.46 0)
			(effects
				(font
					(size 1.27 1.27)
				)
				(hide yes)
			)
		)
		(property "MPN" "TPS65983BAZBHR"
			(at 207.01 116.84 0)
			(effects
				(font
					(size 1.27 1.27)
					(thickness 0.15)
				)
			)
		)
		(property "Manufacturer" "Texas Instruments"
			(at 251.46 134.62 0)
			(effects
				(font
					(size 1.27 1.27)
					(thickness 0.15)
				)
				(justify left bottom)
				(hide yes)
			)
		)
		(property "License" "Apache-2.0"
			(at 251.46 139.7 0)
			(effects
				(font
					(size 1.27 1.27)
					(thickness 0.15)
				)
				(justify left bottom)
				(hide yes)
			)
		)
		(property "Author" "Antmicro"
			(at 251.46 137.16 0)
			(effects
				(font
					(size 1.27 1.27)
					(thickness 0.15)
				)
				(justify left bottom)
				(hide yes)
			)
		)
		(pin "A1"
		)
		(pin "A10"
		)
		(pin "A11"
		)
		(pin "A2"
		)
		(pin "A3"
		)
		(pin "A4"
		)
		(pin "A5"
		)
		(pin "A6"
		)
		(pin "A7"
		)
		(pin "A8"
		)
		(pin "A9"
		)
		(pin "B1"
		)
		(pin "B10"
		)
		(pin "B11"
		)
		(pin "B2"
		)
		(pin "B3"
		)
		(pin "B4"
		)
		(pin "B5"
		)
		(pin "B6"
		)
		(pin "B7"
		)
		(pin "B8"
		)
		(pin "B9"
		)
		(pin "C1"
		)
		(pin "C10"
		)
		(pin "C11"
		)
		(pin "C2"
		)
		(pin "D1"
		)
		(pin "D10"
		)
		(pin "D11"
		)
		(pin "D2"
		)
		(pin "D5"
		)
		(pin "D6"
		)
		(pin "D7"
		)
		(pin "D8"
		)
		(pin "E1"
		)
		(pin "E10"
		)
		(pin "E11"
		)
		(pin "E2"
		)
		(pin "E4"
		)
		(pin "E5"
		)
		(pin "E6"
		)
		(pin "E7"
		)
		(pin "E8"
		)
		(pin "F1"
		)
		(pin "F10"
		)
		(pin "F11"
		)
		(pin "F2"
		)
		(pin "F4"
		)
		(pin "F5"
		)
		(pin "F6"
		)
		(pin "F7"
		)
		(pin "F8"
		)
		(pin "G1"
		)
		(pin "G10"
		)
		(pin "G11"
		)
		(pin "G2"
		)
		(pin "G4"
		)
		(pin "G5"
		)
		(pin "G6"
		)
		(pin "G7"
		)
		(pin "G8"
		)
		(pin "H1"
		)
		(pin "H10"
		)
		(pin "H11"
		)
		(pin "H2"
		)
		(pin "H4"
		)
		(pin "H5"
		)
		(pin "H6"
		)
		(pin "H7"
		)
		(pin "H8"
		)
		(pin "J1"
		)
		(pin "J10"
		)
		(pin "J11"
		)
		(pin "J2"
		)
		(pin "K1"
		)
		(pin "K10"
		)
		(pin "K11"
		)
		(pin "K2"
		)
		(pin "K3"
		)
		(pin "K4"
		)
		(pin "K5"
		)
		(pin "K6"
		)
		(pin "K7"
		)
		(pin "K8"
		)
		(pin "K9"
		)
		(pin "L1"
		)
		(pin "L10"
		)
		(pin "L11"
		)
		(pin "L2"
		)
		(pin "L3"
		)
		(pin "L4"
		)
		(pin "L5"
		)
		(pin "L6"
		)
		(pin "L7"
		)
		(pin "L8"
		)
		(pin "L9"
		)
		(instances
			(project "thunderbolt-gpu-adapter"
				(path ""
					(reference "U3")
					(unit 1)
				)
			)
			(project "thunderbolt-to-10gbe-adapter"
				(path ""
					(reference "U3")
					(unit 1)
				)
			)
		)
	)
	(symbol
		(lib_id "antmicropower:GND")
		(at 259.08 167.64 0)
		(unit 1)
		(exclude_from_sim no)
		(in_bom yes)
		(on_board yes)
		(dnp no)
		(property "Reference" "#PWR049"
			(at 259.08 173.99 0)
			(effects
				(font
					(size 1.27 1.27)
				)
				(hide yes)
			)
		)
		(property "Value" "GND"
			(at 259.08 171.45 0)
			(effects
				(font
					(size 1.27 1.27)
				)
			)
		)
		(property "Footprint" ""
			(at 259.08 167.64 0)
			(effects
				(font
					(size 1.27 1.27)
				)
				(hide yes)
			)
		)
		(property "Datasheet" ""
			(at 259.08 167.64 0)
			(effects
				(font
					(size 1.27 1.27)
				)
				(hide yes)
			)
		)
		(property "Description" ""
			(at 259.08 167.64 0)
			(effects
				(font
					(size 1.27 1.27)
				)
				(hide yes)
			)
		)
		(property "Author" "Antmicro"
			(at 267.97 175.26 0)
			(effects
				(font
					(size 1.27 1.27)
					(thickness 0.15)
				)
				(justify left bottom)
				(hide yes)
			)
		)
		(property "License" "Apache-2.0"
			(at 267.97 177.8 0)
			(effects
				(font
					(size 1.27 1.27)
					(thickness 0.15)
				)
				(justify left bottom)
				(hide yes)
			)
		)
		(pin "1"
		)
		(instances
			(project "thunderbolt-gpu-adapter"
				(path ""
					(reference "#PWR062")
					(unit 1)
				)
			)
			(project "thunderbolt-to-10gbe-adapter"
				(path ""
					(reference "#PWR049")
					(unit 1)
				)
			)
		)
	)
	(symbol
		(lib_id "antmicroResistors0402:R_10k_0402")
		(at 168.91 170.18 0)
		(unit 1)
		(exclude_from_sim no)
		(in_bom yes)
		(on_board yes)
		(dnp no)
		(property "Reference" "R14"
			(at 167.64 168.91 0)
			(effects
				(font
					(size 1.27 1.27)
					(thickness 0.15)
				)
			)
		)
		(property "Value" "R_10k_0402"
			(at 189.23 182.88 0)
			(effects
				(font
					(size 1.27 1.27)
					(thickness 0.15)
				)
				(justify left bottom)
				(hide yes)
			)
		)
		(property "Footprint" "antmicro-footprints:R_0402_1005Metric"
			(at 189.23 185.42 0)
			(effects
				(font
					(size 1.27 1.27)
					(thickness 0.15)
				)
				(justify left bottom)
				(hide yes)
			)
		)
		(property "Datasheet" "https://www.bourns.com/docs/product-datasheets/cr.pdf"
			(at 189.23 187.96 0)
			(effects
				(font
					(size 1.27 1.27)
					(thickness 0.15)
				)
				(justify left bottom)
				(hide yes)
			)
		)
		(property "Description" "SMD Chip Resistor, 10 kohm, ± 1%, 62.5 mW, 0402 [1005 Metric], Thick Film, General Purpose"
			(at 168.91 170.18 0)
			(effects
				(font
					(size 1.27 1.27)
				)
				(hide yes)
			)
		)
		(property "MPN" "CR0402-FX-1002GLF"
			(at 189.23 190.5 0)
			(effects
				(font
					(size 1.27 1.27)
					(thickness 0.15)
				)
				(justify left bottom)
				(hide yes)
			)
		)
		(property "Manufacturer" "Bourns"
			(at 189.23 193.04 0)
			(effects
				(font
					(size 1.27 1.27)
					(thickness 0.15)
				)
				(justify left bottom)
				(hide yes)
			)
		)
		(property "License" "Apache-2.0"
			(at 189.23 195.58 0)
			(effects
				(font
					(size 1.27 1.27)
					(thickness 0.15)
				)
				(justify left bottom)
				(hide yes)
			)
		)
		(property "Val" "10k"
			(at 175.26 168.91 0)
			(effects
				(font
					(size 1.27 1.27)
					(thickness 0.15)
				)
			)
		)
		(property "Tolerance" "1%"
			(at 189.23 180.34 0)
			(effects
				(font
					(size 1.27 1.27)
				)
				(justify left bottom)
				(hide yes)
			)
		)
		(property "Author" "Antmicro"
			(at 189.23 198.12 0)
			(effects
				(font
					(size 1.27 1.27)
					(thickness 0.15)
				)
				(justify left bottom)
				(hide yes)
			)
		)
		(pin "1"
		)
		(pin "2"
		)
		(instances
			(project "thunderbolt-gpu-adapter"
				(path ""
					(reference "R16")
					(unit 1)
				)
			)
			(project "thunderbolt-to-10gbe-adapter"
				(path ""
					(reference "R14")
					(unit 1)
				)
			)
		)
	)
	(symbol
		(lib_id "antmicroCapacitors0402:C_220p_0402")
		(at 285.75 166.37 90)
		(unit 1)
		(exclude_from_sim no)
		(in_bom yes)
		(on_board yes)
		(dnp no)
		(fields_autoplaced yes)
		(property "Reference" "C31"
			(at 288.29 162.5536 90)
			(effects
				(font
					(size 1.27 1.27)
					(thickness 0.15)
				)
				(justify right)
			)
		)
		(property "Value" "C_220p_0402"
			(at 295.91 146.05 0)
			(effects
				(font
					(size 1.27 1.27)
					(thickness 0.15)
				)
				(justify left bottom)
				(hide yes)
			)
		)
		(property "Footprint" "antmicro-footprints:C_0402_1005Metric"
			(at 298.45 146.05 0)
			(effects
				(font
					(size 1.27 1.27)
					(thickness 0.15)
				)
				(justify left bottom)
				(hide yes)
			)
		)
		(property "Datasheet" "https://spicat.kyocera-avx.com/product/mlcc/chartview/04025C221JAT2A/"
			(at 300.99 146.05 0)
			(effects
				(font
					(size 1.27 1.27)
					(thickness 0.15)
				)
				(justify left bottom)
				(hide yes)
			)
		)
		(property "Description" "SMD Multilayer Ceramic Capacitor, 220 pF, 50 V, 0402 [1005 Metric], ± 10%, X7R, MC"
			(at 285.75 166.37 0)
			(effects
				(font
					(size 1.27 1.27)
				)
				(hide yes)
			)
		)
		(property "MPN" "04025C221JAT2A"
			(at 303.53 146.05 0)
			(effects
				(font
					(size 1.27 1.27)
					(thickness 0.15)
				)
				(justify left bottom)
				(hide yes)
			)
		)
		(property "Manufacturer" "KYOCERA AVX"
			(at 306.07 146.05 0)
			(effects
				(font
					(size 1.27 1.27)
					(thickness 0.15)
				)
				(justify left bottom)
				(hide yes)
			)
		)
		(property "License" "Apache-2.0"
			(at 308.61 146.05 0)
			(effects
				(font
					(size 1.27 1.27)
					(thickness 0.15)
				)
				(justify left bottom)
				(hide yes)
			)
		)
		(property "Val" "220p"
			(at 288.29 165.0936 90)
			(effects
				(font
					(size 1.27 1.27)
					(thickness 0.15)
				)
				(justify right)
			)
		)
		(property "Voltage" ""
			(at 313.69 146.05 0)
			(effects
				(font
					(size 1.27 1.27)
				)
				(justify left bottom)
				(hide yes)
			)
		)
		(property "Dielectric" ""
			(at 316.23 146.05 0)
			(effects
				(font
					(size 1.27 1.27)
				)
				(justify left bottom)
				(hide yes)
			)
		)
		(property "Author" "Antmicro"
			(at 311.15 146.05 0)
			(effects
				(font
					(size 1.27 1.27)
					(thickness 0.15)
				)
				(justify left bottom)
				(hide yes)
			)
		)
		(pin "1"
		)
		(pin "2"
		)
		(instances
			(project "thunderbolt-gpu-adapter"
				(path ""
					(reference "C49")
					(unit 1)
				)
			)
			(project "thunderbolt-to-10gbe-adapter"
				(path ""
					(reference "C31")
					(unit 1)
				)
			)
		)
	)
	(symbol
		(lib_id "antmicropower:GND")
		(at 257.81 140.97 0)
		(unit 1)
		(exclude_from_sim no)
		(in_bom yes)
		(on_board yes)
		(dnp no)
		(property "Reference" "#PWR048"
			(at 257.81 147.32 0)
			(effects
				(font
					(size 1.27 1.27)
				)
				(hide yes)
			)
		)
		(property "Value" "GND"
			(at 257.81 144.78 0)
			(effects
				(font
					(size 1.27 1.27)
				)
			)
		)
		(property "Footprint" ""
			(at 257.81 140.97 0)
			(effects
				(font
					(size 1.27 1.27)
				)
				(hide yes)
			)
		)
		(property "Datasheet" ""
			(at 257.81 140.97 0)
			(effects
				(font
					(size 1.27 1.27)
				)
				(hide yes)
			)
		)
		(property "Description" ""
			(at 257.81 140.97 0)
			(effects
				(font
					(size 1.27 1.27)
				)
				(hide yes)
			)
		)
		(property "Author" "Antmicro"
			(at 266.7 148.59 0)
			(effects
				(font
					(size 1.27 1.27)
					(thickness 0.15)
				)
				(justify left bottom)
				(hide yes)
			)
		)
		(property "License" "Apache-2.0"
			(at 266.7 151.13 0)
			(effects
				(font
					(size 1.27 1.27)
					(thickness 0.15)
				)
				(justify left bottom)
				(hide yes)
			)
		)
		(pin "1"
		)
		(instances
			(project "thunderbolt-gpu-adapter"
				(path ""
					(reference "#PWR0218")
					(unit 1)
				)
			)
			(project "thunderbolt-to-10gbe-adapter"
				(path ""
					(reference "#PWR048")
					(unit 1)
				)
			)
		)
	)
	(symbol
		(lib_id "antmicroResistors0402:R_100k_0402")
		(at 240.03 210.82 0)
		(unit 1)
		(exclude_from_sim no)
		(in_bom yes)
		(on_board yes)
		(dnp no)
		(property "Reference" "R24"
			(at 238.125 209.55 0)
			(effects
				(font
					(size 1.27 1.27)
					(thickness 0.15)
				)
			)
		)
		(property "Value" "R_100k_0402"
			(at 260.35 223.52 0)
			(effects
				(font
					(size 1.27 1.27)
					(thickness 0.15)
				)
				(justify left bottom)
				(hide yes)
			)
		)
		(property "Footprint" "antmicro-footprints:R_0402_1005Metric"
			(at 260.35 226.06 0)
			(effects
				(font
					(size 1.27 1.27)
					(thickness 0.15)
				)
				(justify left bottom)
				(hide yes)
			)
		)
		(property "Datasheet" "https://www.bourns.com/docs/product-datasheets/cr.pdf"
			(at 260.35 228.6 0)
			(effects
				(font
					(size 1.27 1.27)
					(thickness 0.15)
				)
				(justify left bottom)
				(hide yes)
			)
		)
		(property "Description" "SMD Chip Resistor, 100 kohm, ± 1%, 62.5 mW, 0402 [1005 Metric], Thick Film, General Purpose"
			(at 240.03 210.82 0)
			(effects
				(font
					(size 1.27 1.27)
				)
				(hide yes)
			)
		)
		(property "MPN" "CR0402-FX-1003GLF"
			(at 260.35 231.14 0)
			(effects
				(font
					(size 1.27 1.27)
					(thickness 0.15)
				)
				(justify left bottom)
				(hide yes)
			)
		)
		(property "Manufacturer" "Bourns"
			(at 260.35 233.68 0)
			(effects
				(font
					(size 1.27 1.27)
					(thickness 0.15)
				)
				(justify left bottom)
				(hide yes)
			)
		)
		(property "License" "Apache-2.0"
			(at 260.35 236.22 0)
			(effects
				(font
					(size 1.27 1.27)
					(thickness 0.15)
				)
				(justify left bottom)
				(hide yes)
			)
		)
		(property "Val" "100k"
			(at 247.015 209.55 0)
			(effects
				(font
					(size 1.27 1.27)
					(thickness 0.15)
				)
			)
		)
		(property "Tolerance" "1%"
			(at 260.35 220.98 0)
			(effects
				(font
					(size 1.27 1.27)
				)
				(justify left bottom)
				(hide yes)
			)
		)
		(property "Author" "Antmicro"
			(at 260.35 238.76 0)
			(effects
				(font
					(size 1.27 1.27)
					(thickness 0.15)
				)
				(justify left bottom)
				(hide yes)
			)
		)
		(pin "1"
		)
		(pin "2"
		)
		(instances
			(project "thunderbolt-gpu-adapter"
				(path ""
					(reference "R30")
					(unit 1)
				)
			)
			(project "thunderbolt-to-10gbe-adapter"
				(path ""
					(reference "R24")
					(unit 1)
				)
			)
		)
	)
	(symbol
		(lib_id "antmicroCapacitorsmisc:C_22u_25V_0805")
		(at 138.43 50.8 90)
		(unit 1)
		(exclude_from_sim no)
		(in_bom yes)
		(on_board yes)
		(dnp no)
		(property "Reference" "C9"
			(at 140.208 45.7201 90)
			(effects
				(font
					(size 1.27 1.27)
					(thickness 0.15)
				)
				(justify right)
			)
		)
		(property "Value" "C_22u_25V_0805"
			(at 148.59 30.48 0)
			(effects
				(font
					(size 1.27 1.27)
					(thickness 0.15)
				)
				(justify left bottom)
				(hide yes)
			)
		)
		(property "Footprint" "antmicro-footprints:C_0805_2012Metric"
			(at 151.13 30.48 0)
			(effects
				(font
					(size 1.27 1.27)
					(thickness 0.15)
				)
				(justify left bottom)
				(hide yes)
			)
		)
		(property "Datasheet" "https://product.samsungsem.com/mlcc/CL21A226MAYNNN.do"
			(at 153.67 30.48 0)
			(effects
				(font
					(size 1.27 1.27)
					(thickness 0.15)
				)
				(justify left bottom)
				(hide yes)
			)
		)
		(property "Description" "SMT Multilayer Ceramic Capacitor, 22uF, +/-20%, 25V, X5R, 0805 [2012 Metric]"
			(at 171.45 30.48 0)
			(effects
				(font
					(size 1.27 1.27)
				)
				(justify left bottom)
				(hide yes)
			)
		)
		(property "MPN" "CL21A226MAYNNNE"
			(at 156.21 30.48 0)
			(effects
				(font
					(size 1.27 1.27)
					(thickness 0.15)
				)
				(justify left bottom)
				(hide yes)
			)
		)
		(property "Manufacturer" "Samsung Electro-Mechanics"
			(at 158.75 30.48 0)
			(effects
				(font
					(size 1.27 1.27)
					(thickness 0.15)
				)
				(justify left bottom)
				(hide yes)
			)
		)
		(property "License" "Apache-2.0"
			(at 161.29 30.48 0)
			(effects
				(font
					(size 1.27 1.27)
					(thickness 0.15)
				)
				(justify left bottom)
				(hide yes)
			)
		)
		(property "Author" "Antmicro"
			(at 163.83 30.48 0)
			(effects
				(font
					(size 1.27 1.27)
					(thickness 0.15)
				)
				(justify left bottom)
				(hide yes)
			)
		)
		(property "Val" "22u"
			(at 140.208 48.2601 90)
			(effects
				(font
					(size 1.27 1.27)
					(thickness 0.15)
				)
				(justify right)
			)
		)
		(property "Voltage" "25V"
			(at 140.208 50.8 90)
			(effects
				(font
					(size 1.27 1.27)
				)
				(justify right)
			)
		)
		(property "Dielectric" "X5R"
			(at 168.91 30.48 0)
			(effects
				(font
					(size 1.27 1.27)
				)
				(justify left bottom)
				(hide yes)
			)
		)
		(property "Public" "False"
			(at 171.45 30.48 0)
			(effects
				(font
					(size 1.27 1.27)
				)
				(justify left bottom)
				(hide yes)
			)
		)
		(pin "2"
		)
		(pin "1"
		)
		(instances
			(project "thunderbolt-to-10gbe-adapter"
				(path ""
					(reference "C9")
					(unit 1)
				)
			)
		)
	)
	(symbol
		(lib_id "antmicroFerriteBeadsandChips:FB_30Z_8.5A_Murata-BLM21SN_0805")
		(at 273.05 129.54 0)
		(mirror x)
		(unit 1)
		(exclude_from_sim no)
		(in_bom yes)
		(on_board yes)
		(dnp no)
		(property "Reference" "FB1"
			(at 275.59 124.46 0)
			(effects
				(font
					(size 1.27 1.27)
					(thickness 0.15)
				)
			)
		)
		(property "Value" "FB_30Z_8.5A_Murata-BLM21SN_0805"
			(at 280.035 126.365 0)
			(effects
				(font
					(size 1.27 1.27)
					(thickness 0.15)
				)
				(hide yes)
			)
		)
		(property "Footprint" "antmicro-footprints:FB_0805_2012Metric"
			(at 287.02 124.46 0)
			(effects
				(font
					(size 1.27 1.27)
					(thickness 0.15)
				)
				(justify left bottom)
				(hide yes)
			)
		)
		(property "Datasheet" "https://www.murata.com/en-sg/products/productdata/8796738977822/ENFA0005.pdf?1519270210000"
			(at 287.02 121.92 0)
			(effects
				(font
					(size 1.27 1.27)
					(thickness 0.15)
				)
				(justify left bottom)
				(hide yes)
			)
		)
		(property "Description" "Ferrite Bead, 0805 [2012 Metric], 30 ohm, 8.5 A, BLM21SN, 0.004 ohm, ± 10ohm, DC power line"
			(at 273.05 129.54 0)
			(effects
				(font
					(size 1.27 1.27)
				)
				(hide yes)
			)
		)
		(property "MPN" "BLM21SN300SZ1D"
			(at 287.02 119.38 0)
			(effects
				(font
					(size 1.27 1.27)
					(thickness 0.15)
				)
				(justify left bottom)
				(hide yes)
			)
		)
		(property "Manufacturer" "Murata"
			(at 287.02 116.84 0)
			(effects
				(font
					(size 1.27 1.27)
					(thickness 0.15)
				)
				(justify left bottom)
				(hide yes)
			)
		)
		(property "License" "Apache-2.0"
			(at 287.02 111.76 0)
			(effects
				(font
					(size 1.27 1.27)
					(thickness 0.15)
				)
				(justify left bottom)
				(hide yes)
			)
		)
		(property "Author" "Antmicro"
			(at 287.02 114.3 0)
			(effects
				(font
					(size 1.27 1.27)
					(thickness 0.15)
				)
				(justify left bottom)
				(hide yes)
			)
		)
		(property "Val" "30Z/8.5A"
			(at 270.51 125.73 0)
			(effects
				(font
					(size 1.27 1.27)
				)
				(justify left bottom)
			)
		)
		(property "Current" ""
			(at 293.37 106.68 0)
			(effects
				(font
					(size 1.27 1.27)
					(thickness 0.15)
				)
				(justify left bottom)
				(hide yes)
			)
		)
		(pin "1"
		)
		(pin "2"
		)
		(instances
			(project "thunderbolt-gpu-adapter"
				(path ""
					(reference "FB8")
					(unit 1)
				)
			)
			(project "thunderbolt-to-10gbe-adapter"
				(path ""
					(reference "FB1")
					(unit 1)
				)
			)
		)
	)
	(symbol
		(lib_id "antmicropower:+3V3")
		(at 132.08 139.7 0)
		(unit 1)
		(exclude_from_sim no)
		(in_bom yes)
		(on_board yes)
		(dnp no)
		(property "Reference" "#PWR020"
			(at 147.32 139.7 0)
			(effects
				(font
					(size 1.27 1.27)
					(thickness 0.15)
				)
				(justify left bottom)
				(hide yes)
			)
		)
		(property "Value" "+3V3_TB"
			(at 132.08 135.89 0)
			(effects
				(font
					(size 1.27 1.27)
					(thickness 0.15)
				)
			)
		)
		(property "Footprint" ""
			(at 147.32 147.32 0)
			(effects
				(font
					(size 1.27 1.27)
					(thickness 0.15)
				)
				(justify left bottom)
				(hide yes)
			)
		)
		(property "Datasheet" ""
			(at 147.32 149.86 0)
			(effects
				(font
					(size 1.27 1.27)
					(thickness 0.15)
				)
				(justify left bottom)
				(hide yes)
			)
		)
		(property "Description" ""
			(at 147.32 152.4 0)
			(effects
				(font
					(size 1.27 1.27)
				)
				(justify left bottom)
				(hide yes)
			)
		)
		(property "Author" "Antmicro"
			(at 147.32 142.24 0)
			(effects
				(font
					(size 1.27 1.27)
					(thickness 0.15)
				)
				(justify left bottom)
				(hide yes)
			)
		)
		(property "License" "Apache-2.0"
			(at 147.32 144.78 0)
			(effects
				(font
					(size 1.27 1.27)
					(thickness 0.15)
				)
				(justify left bottom)
				(hide yes)
			)
		)
		(pin "1"
		)
		(instances
			(project "thunderbolt-to-10gbe-adapter"
				(path ""
					(reference "#PWR020")
					(unit 1)
				)
			)
		)
	)
	(symbol
		(lib_id "antmicroResistors0402:R_100k_0402")
		(at 240.03 231.14 0)
		(unit 1)
		(exclude_from_sim no)
		(in_bom yes)
		(on_board yes)
		(dnp no)
		(property "Reference" "R27"
			(at 238.125 229.87 0)
			(effects
				(font
					(size 1.27 1.27)
					(thickness 0.15)
				)
			)
		)
		(property "Value" "R_100k_0402"
			(at 260.35 243.84 0)
			(effects
				(font
					(size 1.27 1.27)
					(thickness 0.15)
				)
				(justify left bottom)
				(hide yes)
			)
		)
		(property "Footprint" "antmicro-footprints:R_0402_1005Metric"
			(at 260.35 246.38 0)
			(effects
				(font
					(size 1.27 1.27)
					(thickness 0.15)
				)
				(justify left bottom)
				(hide yes)
			)
		)
		(property "Datasheet" "https://www.bourns.com/docs/product-datasheets/cr.pdf"
			(at 260.35 248.92 0)
			(effects
				(font
					(size 1.27 1.27)
					(thickness 0.15)
				)
				(justify left bottom)
				(hide yes)
			)
		)
		(property "Description" "SMD Chip Resistor, 100 kohm, ± 1%, 62.5 mW, 0402 [1005 Metric], Thick Film, General Purpose"
			(at 240.03 231.14 0)
			(effects
				(font
					(size 1.27 1.27)
				)
				(hide yes)
			)
		)
		(property "MPN" "CR0402-FX-1003GLF"
			(at 260.35 251.46 0)
			(effects
				(font
					(size 1.27 1.27)
					(thickness 0.15)
				)
				(justify left bottom)
				(hide yes)
			)
		)
		(property "Manufacturer" "Bourns"
			(at 260.35 254 0)
			(effects
				(font
					(size 1.27 1.27)
					(thickness 0.15)
				)
				(justify left bottom)
				(hide yes)
			)
		)
		(property "License" "Apache-2.0"
			(at 260.35 256.54 0)
			(effects
				(font
					(size 1.27 1.27)
					(thickness 0.15)
				)
				(justify left bottom)
				(hide yes)
			)
		)
		(property "Val" "100k"
			(at 247.015 229.87 0)
			(effects
				(font
					(size 1.27 1.27)
					(thickness 0.15)
				)
			)
		)
		(property "Tolerance" "1%"
			(at 260.35 241.3 0)
			(effects
				(font
					(size 1.27 1.27)
				)
				(justify left bottom)
				(hide yes)
			)
		)
		(property "Author" "Antmicro"
			(at 260.35 259.08 0)
			(effects
				(font
					(size 1.27 1.27)
					(thickness 0.15)
				)
				(justify left bottom)
				(hide yes)
			)
		)
		(pin "1"
		)
		(pin "2"
		)
		(instances
			(project "thunderbolt-gpu-adapter"
				(path ""
					(reference "R33")
					(unit 1)
				)
			)
			(project "thunderbolt-to-10gbe-adapter"
				(path ""
					(reference "R27")
					(unit 1)
				)
			)
		)
	)
	(symbol
		(lib_id "antmicroResistors0402:R_330R_0402")
		(at 266.7 76.2 90)
		(unit 1)
		(exclude_from_sim no)
		(in_bom yes)
		(on_board yes)
		(dnp no)
		(fields_autoplaced yes)
		(property "Reference" "R32"
			(at 269.24 72.39 90)
			(effects
				(font
					(size 1.27 1.27)
					(thickness 0.15)
				)
				(justify right)
			)
		)
		(property "Value" "R_330R_0402"
			(at 279.4 55.88 0)
			(effects
				(font
					(size 1.27 1.27)
					(thickness 0.15)
				)
				(justify left bottom)
				(hide yes)
			)
		)
		(property "Footprint" "antmicro-footprints:R_0402_1005Metric"
			(at 281.94 55.88 0)
			(effects
				(font
					(size 1.27 1.27)
					(thickness 0.15)
				)
				(justify left bottom)
				(hide yes)
			)
		)
		(property "Datasheet" "https://www.bourns.com/docs/product-datasheets/cr.pdf"
			(at 284.48 55.88 0)
			(effects
				(font
					(size 1.27 1.27)
					(thickness 0.15)
				)
				(justify left bottom)
				(hide yes)
			)
		)
		(property "Description" "SMD Chip Resistor, 330 ohm, ± 1%, 62.5 mW, 0402 [1005 Metric], Thick Film, General Purpose"
			(at 266.7 76.2 0)
			(effects
				(font
					(size 1.27 1.27)
				)
				(hide yes)
			)
		)
		(property "MPN" "CR0402-FX-3300GLF"
			(at 287.02 55.88 0)
			(effects
				(font
					(size 1.27 1.27)
					(thickness 0.15)
				)
				(justify left bottom)
				(hide yes)
			)
		)
		(property "Manufacturer" "Bourns"
			(at 289.56 55.88 0)
			(effects
				(font
					(size 1.27 1.27)
					(thickness 0.15)
				)
				(justify left bottom)
				(hide yes)
			)
		)
		(property "License" "Apache-2.0"
			(at 292.1 55.88 0)
			(effects
				(font
					(size 1.27 1.27)
					(thickness 0.15)
				)
				(justify left bottom)
				(hide yes)
			)
		)
		(property "Val" "330R"
			(at 269.24 74.93 90)
			(effects
				(font
					(size 1.27 1.27)
					(thickness 0.15)
				)
				(justify right)
			)
		)
		(property "Tolerance" "1%"
			(at 276.86 55.88 0)
			(effects
				(font
					(size 1.27 1.27)
				)
				(justify left bottom)
				(hide yes)
			)
		)
		(property "Author" "Antmicro"
			(at 294.64 55.88 0)
			(effects
				(font
					(size 1.27 1.27)
					(thickness 0.15)
				)
				(justify left bottom)
				(hide yes)
			)
		)
		(pin "1"
		)
		(pin "2"
		)
		(instances
			(project "thunderbolt-to-10gbe-adapter"
				(path ""
					(reference "R32")
					(unit 1)
				)
			)
		)
	)
	(symbol
		(lib_id "antmicropower:GND")
		(at 276.86 167.64 0)
		(unit 1)
		(exclude_from_sim no)
		(in_bom yes)
		(on_board yes)
		(dnp no)
		(property "Reference" "#PWR053"
			(at 276.86 173.99 0)
			(effects
				(font
					(size 1.27 1.27)
				)
				(hide yes)
			)
		)
		(property "Value" "GND"
			(at 276.86 171.45 0)
			(effects
				(font
					(size 1.27 1.27)
				)
			)
		)
		(property "Footprint" ""
			(at 276.86 167.64 0)
			(effects
				(font
					(size 1.27 1.27)
				)
				(hide yes)
			)
		)
		(property "Datasheet" ""
			(at 276.86 167.64 0)
			(effects
				(font
					(size 1.27 1.27)
				)
				(hide yes)
			)
		)
		(property "Description" ""
			(at 276.86 167.64 0)
			(effects
				(font
					(size 1.27 1.27)
				)
				(hide yes)
			)
		)
		(property "Author" "Antmicro"
			(at 285.75 175.26 0)
			(effects
				(font
					(size 1.27 1.27)
					(thickness 0.15)
				)
				(justify left bottom)
				(hide yes)
			)
		)
		(property "License" "Apache-2.0"
			(at 285.75 177.8 0)
			(effects
				(font
					(size 1.27 1.27)
					(thickness 0.15)
				)
				(justify left bottom)
				(hide yes)
			)
		)
		(pin "1"
		)
		(instances
			(project "thunderbolt-gpu-adapter"
				(path ""
					(reference "#PWR070")
					(unit 1)
				)
			)
			(project "thunderbolt-to-10gbe-adapter"
				(path ""
					(reference "#PWR053")
					(unit 1)
				)
			)
		)
	)
	(symbol
		(lib_id "antmicroResistors0402:R_2k2_0402")
		(at 138.43 151.13 90)
		(unit 1)
		(exclude_from_sim no)
		(in_bom yes)
		(on_board yes)
		(dnp no)
		(property "Reference" "R9"
			(at 139.7 147.32 90)
			(effects
				(font
					(size 1.27 1.27)
					(thickness 0.15)
				)
				(justify right)
			)
		)
		(property "Value" "R_2k2_0402"
			(at 151.13 130.81 0)
			(effects
				(font
					(size 1.27 1.27)
					(thickness 0.15)
				)
				(justify left bottom)
				(hide yes)
			)
		)
		(property "Footprint" "antmicro-footprints:R_0402_1005Metric"
			(at 153.67 130.81 0)
			(effects
				(font
					(size 1.27 1.27)
					(thickness 0.15)
				)
				(justify left bottom)
				(hide yes)
			)
		)
		(property "Datasheet" "https://www.bourns.com/docs/product-datasheets/cr.pdf"
			(at 156.21 130.81 0)
			(effects
				(font
					(size 1.27 1.27)
					(thickness 0.15)
				)
				(justify left bottom)
				(hide yes)
			)
		)
		(property "Description" "SMD Chip Resistor, 2.2 kohm, ± 1%, 62.5 mW, 0402 [1005 Metric], Thick Film, General Purpose"
			(at 138.43 151.13 0)
			(effects
				(font
					(size 1.27 1.27)
				)
				(hide yes)
			)
		)
		(property "MPN" "CR0402-FX-2201GLF"
			(at 158.75 130.81 0)
			(effects
				(font
					(size 1.27 1.27)
					(thickness 0.15)
				)
				(justify left bottom)
				(hide yes)
			)
		)
		(property "Manufacturer" "Bourns"
			(at 161.29 130.81 0)
			(effects
				(font
					(size 1.27 1.27)
					(thickness 0.15)
				)
				(justify left bottom)
				(hide yes)
			)
		)
		(property "License" "Apache-2.0"
			(at 163.83 130.81 0)
			(effects
				(font
					(size 1.27 1.27)
					(thickness 0.15)
				)
				(justify left bottom)
				(hide yes)
			)
		)
		(property "Val" "2k2"
			(at 139.7 149.86 90)
			(effects
				(font
					(size 1.27 1.27)
					(thickness 0.15)
				)
				(justify right)
			)
		)
		(property "Tolerance" "1%"
			(at 148.59 130.81 0)
			(effects
				(font
					(size 1.27 1.27)
				)
				(justify left bottom)
				(hide yes)
			)
		)
		(property "Author" "Antmicro"
			(at 166.37 130.81 0)
			(effects
				(font
					(size 1.27 1.27)
					(thickness 0.15)
				)
				(justify left bottom)
				(hide yes)
			)
		)
		(pin "1"
		)
		(pin "2"
		)
		(instances
			(project "thunderbolt-gpu-adapter"
				(path ""
					(reference "R3")
					(unit 1)
				)
			)
			(project "thunderbolt-to-10gbe-adapter"
				(path ""
					(reference "R9")
					(unit 1)
				)
			)
		)
	)
	(symbol
		(lib_id "antmicropower:GND")
		(at 252.73 152.4 0)
		(unit 1)
		(exclude_from_sim no)
		(in_bom yes)
		(on_board yes)
		(dnp no)
		(property "Reference" "#PWR041"
			(at 252.73 158.75 0)
			(effects
				(font
					(size 1.27 1.27)
				)
				(hide yes)
			)
		)
		(property "Value" "GND"
			(at 252.73 156.21 0)
			(effects
				(font
					(size 1.27 1.27)
				)
			)
		)
		(property "Footprint" ""
			(at 252.73 152.4 0)
			(effects
				(font
					(size 1.27 1.27)
				)
				(hide yes)
			)
		)
		(property "Datasheet" ""
			(at 252.73 152.4 0)
			(effects
				(font
					(size 1.27 1.27)
				)
				(hide yes)
			)
		)
		(property "Description" ""
			(at 252.73 152.4 0)
			(effects
				(font
					(size 1.27 1.27)
				)
				(hide yes)
			)
		)
		(property "Author" "Antmicro"
			(at 261.62 160.02 0)
			(effects
				(font
					(size 1.27 1.27)
					(thickness 0.15)
				)
				(justify left bottom)
				(hide yes)
			)
		)
		(property "License" "Apache-2.0"
			(at 261.62 162.56 0)
			(effects
				(font
					(size 1.27 1.27)
					(thickness 0.15)
				)
				(justify left bottom)
				(hide yes)
			)
		)
		(pin "1"
		)
		(instances
			(project "thunderbolt-gpu-adapter"
				(path ""
					(reference "#PWR053")
					(unit 1)
				)
			)
			(project "thunderbolt-to-10gbe-adapter"
				(path ""
					(reference "#PWR041")
					(unit 1)
				)
			)
		)
	)
	(symbol
		(lib_id "antmicroCapacitors0402:C_10u_0402")
		(at 243.84 137.16 0)
		(unit 1)
		(exclude_from_sim no)
		(in_bom yes)
		(on_board yes)
		(dnp no)
		(property "Reference" "C25"
			(at 243.84 138.43 0)
			(effects
				(font
					(size 1.27 1.27)
					(thickness 0.15)
				)
			)
		)
		(property "Value" "C_10u_0402"
			(at 264.16 147.32 0)
			(effects
				(font
					(size 1.27 1.27)
					(thickness 0.15)
				)
				(justify left bottom)
				(hide yes)
			)
		)
		(property "Footprint" "antmicro-footprints:C_0402_1005Metric"
			(at 264.16 149.86 0)
			(effects
				(font
					(size 1.27 1.27)
					(thickness 0.15)
				)
				(justify left bottom)
				(hide yes)
			)
		)
		(property "Datasheet" "https://www.yageo.com/en/Chart/Download/pdf/CC0402MRX5R5BB106"
			(at 264.16 152.4 0)
			(effects
				(font
					(size 1.27 1.27)
					(thickness 0.15)
				)
				(justify left bottom)
				(hide yes)
			)
		)
		(property "Description" "SMD Multilayer Ceramic Capacitor, 10 µF, 6.3 V, 0402 [1005 Metric], ± 20%, X5R, CC Series"
			(at 243.84 137.16 0)
			(effects
				(font
					(size 1.27 1.27)
				)
				(hide yes)
			)
		)
		(property "MPN" "CC0402MRX5R5BB106"
			(at 264.16 154.94 0)
			(effects
				(font
					(size 1.27 1.27)
					(thickness 0.15)
				)
				(justify left bottom)
				(hide yes)
			)
		)
		(property "Manufacturer" "YAGEO"
			(at 264.16 157.48 0)
			(effects
				(font
					(size 1.27 1.27)
					(thickness 0.15)
				)
				(justify left bottom)
				(hide yes)
			)
		)
		(property "License" "Apache-2.0"
			(at 264.16 160.02 0)
			(effects
				(font
					(size 1.27 1.27)
					(thickness 0.15)
				)
				(justify left bottom)
				(hide yes)
			)
		)
		(property "Val" "10u"
			(at 248.92 138.43 0)
			(effects
				(font
					(size 1.27 1.27)
					(thickness 0.15)
				)
			)
		)
		(property "Voltage" ""
			(at 264.16 165.1 0)
			(effects
				(font
					(size 1.27 1.27)
				)
				(justify left bottom)
				(hide yes)
			)
		)
		(property "Dielectric" ""
			(at 264.16 167.64 0)
			(effects
				(font
					(size 1.27 1.27)
				)
				(justify left bottom)
				(hide yes)
			)
		)
		(property "Author" "Antmicro"
			(at 264.16 162.56 0)
			(effects
				(font
					(size 1.27 1.27)
					(thickness 0.15)
				)
				(justify left bottom)
				(hide yes)
			)
		)
		(pin "1"
		)
		(pin "2"
		)
		(instances
			(project "thunderbolt-gpu-adapter"
				(path ""
					(reference "C39")
					(unit 1)
				)
			)
			(project "thunderbolt-to-10gbe-adapter"
				(path ""
					(reference "C25")
					(unit 1)
				)
			)
		)
	)
	(symbol
		(lib_id "antmicropower:GND")
		(at 166.37 220.98 0)
		(unit 1)
		(exclude_from_sim no)
		(in_bom yes)
		(on_board yes)
		(dnp no)
		(property "Reference" "#PWR029"
			(at 166.37 227.33 0)
			(effects
				(font
					(size 1.27 1.27)
				)
				(hide yes)
			)
		)
		(property "Value" "GND"
			(at 166.37 224.79 0)
			(effects
				(font
					(size 1.27 1.27)
				)
			)
		)
		(property "Footprint" ""
			(at 166.37 220.98 0)
			(effects
				(font
					(size 1.27 1.27)
				)
				(hide yes)
			)
		)
		(property "Datasheet" ""
			(at 166.37 220.98 0)
			(effects
				(font
					(size 1.27 1.27)
				)
				(hide yes)
			)
		)
		(property "Description" ""
			(at 166.37 220.98 0)
			(effects
				(font
					(size 1.27 1.27)
				)
				(hide yes)
			)
		)
		(property "Author" "Antmicro"
			(at 175.26 228.6 0)
			(effects
				(font
					(size 1.27 1.27)
					(thickness 0.15)
				)
				(justify left bottom)
				(hide yes)
			)
		)
		(property "License" "Apache-2.0"
			(at 175.26 231.14 0)
			(effects
				(font
					(size 1.27 1.27)
					(thickness 0.15)
				)
				(justify left bottom)
				(hide yes)
			)
		)
		(pin "1"
		)
		(instances
			(project "thunderbolt-gpu-adapter"
				(path ""
					(reference "#PWR034")
					(unit 1)
				)
			)
			(project "thunderbolt-to-10gbe-adapter"
				(path ""
					(reference "#PWR029")
					(unit 1)
				)
			)
		)
	)
	(symbol
		(lib_id "antmicropower:PWR_FLAG")
		(at 170.18 133.35 0)
		(unit 1)
		(exclude_from_sim no)
		(in_bom yes)
		(on_board yes)
		(dnp no)
		(property "Reference" "#FLG06"
			(at 170.18 131.445 0)
			(effects
				(font
					(size 1.27 1.27)
				)
				(hide yes)
			)
		)
		(property "Value" "PWR_FLAG"
			(at 170.18 129.54 0)
			(effects
				(font
					(size 1.27 1.27)
				)
				(hide yes)
			)
		)
		(property "Footprint" ""
			(at 170.18 133.35 0)
			(effects
				(font
					(size 1.27 1.27)
				)
				(hide yes)
			)
		)
		(property "Datasheet" ""
			(at 170.18 133.35 0)
			(effects
				(font
					(size 1.27 1.27)
				)
				(hide yes)
			)
		)
		(property "Description" ""
			(at 170.18 135.89 0)
			(effects
				(font
					(size 1.27 1.27)
				)
				(justify left bottom)
				(hide yes)
			)
		)
		(pin "1"
		)
		(instances
			(project "thunderbolt-to-10gbe-adapter"
				(path ""
					(reference "#FLG06")
					(unit 1)
				)
			)
		)
	)
	(symbol
		(lib_id "antmicroLEDIndicationDiscrete:LED_G_0603_KP-1608CGCK")
		(at 266.7 68.58 90)
		(unit 1)
		(exclude_from_sim no)
		(in_bom yes)
		(on_board yes)
		(dnp no)
		(fields_autoplaced yes)
		(property "Reference" "D4"
			(at 269.24 64.77 90)
			(effects
				(font
					(size 1.27 1.27)
					(thickness 0.15)
				)
				(justify right)
			)
		)
		(property "Value" "LED_G_0603_KP-1608CGCK"
			(at 262.89 63.5001 90)
			(effects
				(font
					(size 1.27 1.27)
					(thickness 0.15)
				)
				(justify left)
				(hide yes)
			)
		)
		(property "Footprint" "antmicro-footprints:LED_0603_1608Metric_G"
			(at 276.86 45.72 0)
			(effects
				(font
					(size 1.27 1.27)
					(thickness 0.15)
				)
				(justify left bottom)
				(hide yes)
			)
		)
		(property "Datasheet" "http://www.kingbright.com/attachments/file/psearch//000/00/00/KP-1608CGCK(Ver.23B).pdf"
			(at 279.4 45.72 0)
			(effects
				(font
					(size 1.27 1.27)
					(thickness 0.15)
				)
				(justify left bottom)
				(hide yes)
			)
		)
		(property "Description" "LED, Green, SMD, 0603, 20 mA, 2.1 V, 570 nm"
			(at 266.7 68.58 0)
			(effects
				(font
					(size 1.27 1.27)
				)
				(hide yes)
			)
		)
		(property "MPN" "KP-1608CGCK"
			(at 281.94 45.72 0)
			(effects
				(font
					(size 1.27 1.27)
					(thickness 0.15)
				)
				(justify left bottom)
				(hide yes)
			)
		)
		(property "Manufacturer" "Kingbright"
			(at 284.48 45.72 0)
			(effects
				(font
					(size 1.27 1.27)
					(thickness 0.15)
				)
				(justify left bottom)
				(hide yes)
			)
		)
		(property "License" "Apache-2.0"
			(at 289.56 45.72 0)
			(effects
				(font
					(size 1.27 1.27)
					(thickness 0.15)
				)
				(justify left bottom)
				(hide yes)
			)
		)
		(property "Author" "Antmicro"
			(at 287.02 45.72 0)
			(effects
				(font
					(size 1.27 1.27)
					(thickness 0.15)
				)
				(justify left bottom)
				(hide yes)
			)
		)
		(property "Color" "Green"
			(at 269.24 67.31 90)
			(effects
				(font
					(size 1.27 1.27)
				)
				(justify right)
			)
		)
		(pin "1"
		)
		(pin "2"
		)
		(instances
			(project "thunderbolt-to-10gbe-adapter"
				(path ""
					(reference "D4")
					(unit 1)
				)
			)
		)
	)
	(symbol
		(lib_id "antmicropower:GND")
		(at 285.75 167.64 0)
		(unit 1)
		(exclude_from_sim no)
		(in_bom yes)
		(on_board yes)
		(dnp no)
		(property "Reference" "#PWR055"
			(at 285.75 173.99 0)
			(effects
				(font
					(size 1.27 1.27)
				)
				(hide yes)
			)
		)
		(property "Value" "GND"
			(at 285.75 171.45 0)
			(effects
				(font
					(size 1.27 1.27)
				)
			)
		)
		(property "Footprint" ""
			(at 285.75 167.64 0)
			(effects
				(font
					(size 1.27 1.27)
				)
				(hide yes)
			)
		)
		(property "Datasheet" ""
			(at 285.75 167.64 0)
			(effects
				(font
					(size 1.27 1.27)
				)
				(hide yes)
			)
		)
		(property "Description" ""
			(at 285.75 167.64 0)
			(effects
				(font
					(size 1.27 1.27)
				)
				(hide yes)
			)
		)
		(property "Author" "Antmicro"
			(at 294.64 175.26 0)
			(effects
				(font
					(size 1.27 1.27)
					(thickness 0.15)
				)
				(justify left bottom)
				(hide yes)
			)
		)
		(property "License" "Apache-2.0"
			(at 294.64 177.8 0)
			(effects
				(font
					(size 1.27 1.27)
					(thickness 0.15)
				)
				(justify left bottom)
				(hide yes)
			)
		)
		(pin "1"
		)
		(instances
			(project "thunderbolt-gpu-adapter"
				(path ""
					(reference "#PWR072")
					(unit 1)
				)
			)
			(project "thunderbolt-to-10gbe-adapter"
				(path ""
					(reference "#PWR055")
					(unit 1)
				)
			)
		)
	)
	(symbol
		(lib_id "antmicropower:GND")
		(at 165.1 149.86 0)
		(unit 1)
		(exclude_from_sim no)
		(in_bom yes)
		(on_board yes)
		(dnp no)
		(property "Reference" "#PWR028"
			(at 165.1 156.21 0)
			(effects
				(font
					(size 1.27 1.27)
				)
				(hide yes)
			)
		)
		(property "Value" "GND"
			(at 165.1 153.67 0)
			(effects
				(font
					(size 1.27 1.27)
				)
			)
		)
		(property "Footprint" ""
			(at 165.1 149.86 0)
			(effects
				(font
					(size 1.27 1.27)
				)
				(hide yes)
			)
		)
		(property "Datasheet" ""
			(at 165.1 149.86 0)
			(effects
				(font
					(size 1.27 1.27)
				)
				(hide yes)
			)
		)
		(property "Description" ""
			(at 165.1 149.86 0)
			(effects
				(font
					(size 1.27 1.27)
				)
				(hide yes)
			)
		)
		(property "Author" "Antmicro"
			(at 173.99 157.48 0)
			(effects
				(font
					(size 1.27 1.27)
					(thickness 0.15)
				)
				(justify left bottom)
				(hide yes)
			)
		)
		(property "License" "Apache-2.0"
			(at 173.99 160.02 0)
			(effects
				(font
					(size 1.27 1.27)
					(thickness 0.15)
				)
				(justify left bottom)
				(hide yes)
			)
		)
		(pin "1"
		)
		(instances
			(project "thunderbolt-gpu-adapter"
				(path ""
					(reference "#PWR033")
					(unit 1)
				)
			)
			(project "thunderbolt-to-10gbe-adapter"
				(path ""
					(reference "#PWR028")
					(unit 1)
				)
			)
		)
	)
	(symbol
		(lib_id "antmicropower:+3V3")
		(at 288.29 57.15 0)
		(unit 1)
		(exclude_from_sim no)
		(in_bom yes)
		(on_board yes)
		(dnp no)
		(property "Reference" "#PWR056"
			(at 303.53 57.15 0)
			(effects
				(font
					(size 1.27 1.27)
					(thickness 0.15)
				)
				(justify left bottom)
				(hide yes)
			)
		)
		(property "Value" "+3V3_TB"
			(at 288.29 53.34 0)
			(effects
				(font
					(size 1.27 1.27)
					(thickness 0.15)
				)
			)
		)
		(property "Footprint" ""
			(at 303.53 64.77 0)
			(effects
				(font
					(size 1.27 1.27)
					(thickness 0.15)
				)
				(justify left bottom)
				(hide yes)
			)
		)
		(property "Datasheet" ""
			(at 303.53 67.31 0)
			(effects
				(font
					(size 1.27 1.27)
					(thickness 0.15)
				)
				(justify left bottom)
				(hide yes)
			)
		)
		(property "Description" ""
			(at 303.53 69.85 0)
			(effects
				(font
					(size 1.27 1.27)
				)
				(justify left bottom)
				(hide yes)
			)
		)
		(property "Author" "Antmicro"
			(at 303.53 59.69 0)
			(effects
				(font
					(size 1.27 1.27)
					(thickness 0.15)
				)
				(justify left bottom)
				(hide yes)
			)
		)
		(property "License" "Apache-2.0"
			(at 303.53 62.23 0)
			(effects
				(font
					(size 1.27 1.27)
					(thickness 0.15)
				)
				(justify left bottom)
				(hide yes)
			)
		)
		(pin "1"
		)
		(instances
			(project "thunderbolt-to-10gbe-adapter"
				(path ""
					(reference "#PWR056")
					(unit 1)
				)
			)
		)
	)
	(symbol
		(lib_id "antmicroResistors0402:R_8k87_0402")
		(at 214.63 74.93 90)
		(unit 1)
		(exclude_from_sim no)
		(in_bom yes)
		(on_board yes)
		(dnp no)
		(fields_autoplaced yes)
		(property "Reference" "R22"
			(at 217.17 71.12 90)
			(effects
				(font
					(size 1.27 1.27)
					(thickness 0.15)
				)
				(justify right)
			)
		)
		(property "Value" "R_8k87_0402"
			(at 227.33 54.61 0)
			(effects
				(font
					(size 1.27 1.27)
					(thickness 0.15)
				)
				(justify left bottom)
				(hide yes)
			)
		)
		(property "Footprint" "antmicro-footprints:R_0402_1005Metric"
			(at 229.87 54.61 0)
			(effects
				(font
					(size 1.27 1.27)
					(thickness 0.15)
				)
				(justify left bottom)
				(hide yes)
			)
		)
		(property "Datasheet" "https://www.bourns.com/docs/product-datasheets/cr.pdf"
			(at 232.41 54.61 0)
			(effects
				(font
					(size 1.27 1.27)
					(thickness 0.15)
				)
				(justify left bottom)
				(hide yes)
			)
		)
		(property "Description" "SMD Chip Resistor, 8.87 kohm, ± 1%, 100 mW, 0402 [1005 Metric], Thick Film, Precision"
			(at 214.63 74.93 0)
			(effects
				(font
					(size 1.27 1.27)
				)
				(hide yes)
			)
		)
		(property "MPN" "CR0402-FX-8871GLF"
			(at 234.95 54.61 0)
			(effects
				(font
					(size 1.27 1.27)
					(thickness 0.15)
				)
				(justify left bottom)
				(hide yes)
			)
		)
		(property "Manufacturer" "Bourns"
			(at 237.49 54.61 0)
			(effects
				(font
					(size 1.27 1.27)
					(thickness 0.15)
				)
				(justify left bottom)
				(hide yes)
			)
		)
		(property "License" "Apache-2.0"
			(at 240.03 54.61 0)
			(effects
				(font
					(size 1.27 1.27)
					(thickness 0.15)
				)
				(justify left bottom)
				(hide yes)
			)
		)
		(property "Val" "8k87"
			(at 217.17 73.66 90)
			(effects
				(font
					(size 1.27 1.27)
					(thickness 0.15)
				)
				(justify right)
			)
		)
		(property "Tolerance" "1%"
			(at 224.79 54.61 0)
			(effects
				(font
					(size 1.27 1.27)
				)
				(justify left bottom)
				(hide yes)
			)
		)
		(property "Author" "Antmicro"
			(at 242.57 54.61 0)
			(effects
				(font
					(size 1.27 1.27)
					(thickness 0.15)
				)
				(justify left bottom)
				(hide yes)
			)
		)
		(pin "1"
		)
		(pin "2"
		)
		(instances
			(project "thunderbolt-to-10gbe-adapter"
				(path ""
					(reference "R22")
					(unit 1)
				)
			)
		)
	)
	(symbol
		(lib_id "antmicroCapacitors0402:C_10u_0402")
		(at 168.91 149.86 0)
		(unit 1)
		(exclude_from_sim no)
		(in_bom yes)
		(on_board yes)
		(dnp no)
		(property "Reference" "C15"
			(at 168.91 151.13 0)
			(effects
				(font
					(size 1.27 1.27)
					(thickness 0.15)
				)
			)
		)
		(property "Value" "C_10u_0402"
			(at 189.23 160.02 0)
			(effects
				(font
					(size 1.27 1.27)
					(thickness 0.15)
				)
				(justify left bottom)
				(hide yes)
			)
		)
		(property "Footprint" "antmicro-footprints:C_0402_1005Metric"
			(at 189.23 162.56 0)
			(effects
				(font
					(size 1.27 1.27)
					(thickness 0.15)
				)
				(justify left bottom)
				(hide yes)
			)
		)
		(property "Datasheet" "https://www.yageo.com/en/Chart/Download/pdf/CC0402MRX5R5BB106"
			(at 189.23 165.1 0)
			(effects
				(font
					(size 1.27 1.27)
					(thickness 0.15)
				)
				(justify left bottom)
				(hide yes)
			)
		)
		(property "Description" "SMD Multilayer Ceramic Capacitor, 10 µF, 6.3 V, 0402 [1005 Metric], ± 20%, X5R, CC Series"
			(at 168.91 149.86 0)
			(effects
				(font
					(size 1.27 1.27)
				)
				(hide yes)
			)
		)
		(property "MPN" "CC0402MRX5R5BB106"
			(at 189.23 167.64 0)
			(effects
				(font
					(size 1.27 1.27)
					(thickness 0.15)
				)
				(justify left bottom)
				(hide yes)
			)
		)
		(property "Manufacturer" "YAGEO"
			(at 189.23 170.18 0)
			(effects
				(font
					(size 1.27 1.27)
					(thickness 0.15)
				)
				(justify left bottom)
				(hide yes)
			)
		)
		(property "License" "Apache-2.0"
			(at 189.23 172.72 0)
			(effects
				(font
					(size 1.27 1.27)
					(thickness 0.15)
				)
				(justify left bottom)
				(hide yes)
			)
		)
		(property "Val" "10u"
			(at 173.99 151.13 0)
			(effects
				(font
					(size 1.27 1.27)
					(thickness 0.15)
				)
			)
		)
		(property "Voltage" ""
			(at 189.23 177.8 0)
			(effects
				(font
					(size 1.27 1.27)
				)
				(justify left bottom)
				(hide yes)
			)
		)
		(property "Dielectric" ""
			(at 189.23 180.34 0)
			(effects
				(font
					(size 1.27 1.27)
				)
				(justify left bottom)
				(hide yes)
			)
		)
		(property "Author" "Antmicro"
			(at 189.23 175.26 0)
			(effects
				(font
					(size 1.27 1.27)
					(thickness 0.15)
				)
				(justify left bottom)
				(hide yes)
			)
		)
		(pin "1"
		)
		(pin "2"
		)
		(instances
			(project "thunderbolt-to-10gbe-adapter"
				(path ""
					(reference "C15")
					(unit 1)
				)
			)
		)
	)
	(symbol
		(lib_id "antmicropower:GND")
		(at 252.73 147.32 0)
		(unit 1)
		(exclude_from_sim no)
		(in_bom yes)
		(on_board yes)
		(dnp no)
		(property "Reference" "#PWR040"
			(at 252.73 153.67 0)
			(effects
				(font
					(size 1.27 1.27)
				)
				(hide yes)
			)
		)
		(property "Value" "GND"
			(at 252.73 151.13 0)
			(effects
				(font
					(size 1.27 1.27)
				)
			)
		)
		(property "Footprint" ""
			(at 252.73 147.32 0)
			(effects
				(font
					(size 1.27 1.27)
				)
				(hide yes)
			)
		)
		(property "Datasheet" ""
			(at 252.73 147.32 0)
			(effects
				(font
					(size 1.27 1.27)
				)
				(hide yes)
			)
		)
		(property "Description" ""
			(at 252.73 147.32 0)
			(effects
				(font
					(size 1.27 1.27)
				)
				(hide yes)
			)
		)
		(property "Author" "Antmicro"
			(at 261.62 154.94 0)
			(effects
				(font
					(size 1.27 1.27)
					(thickness 0.15)
				)
				(justify left bottom)
				(hide yes)
			)
		)
		(property "License" "Apache-2.0"
			(at 261.62 157.48 0)
			(effects
				(font
					(size 1.27 1.27)
					(thickness 0.15)
				)
				(justify left bottom)
				(hide yes)
			)
		)
		(pin "1"
		)
		(instances
			(project "thunderbolt-gpu-adapter"
				(path ""
					(reference "#PWR052")
					(unit 1)
				)
			)
			(project "thunderbolt-to-10gbe-adapter"
				(path ""
					(reference "#PWR040")
					(unit 1)
				)
			)
		)
	)
	(symbol
		(lib_id "antmicroCapacitors0402:C_1u_25V_0402")
		(at 229.87 71.12 90)
		(unit 1)
		(exclude_from_sim no)
		(in_bom yes)
		(on_board yes)
		(dnp no)
		(property "Reference" "C18"
			(at 231.648 67.31 90)
			(effects
				(font
					(size 1.27 1.27)
					(thickness 0.15)
				)
				(justify right)
			)
		)
		(property "Value" "C_1u_25V_0402"
			(at 240.03 50.8 0)
			(effects
				(font
					(size 1.27 1.27)
					(thickness 0.15)
				)
				(justify left bottom)
				(hide yes)
			)
		)
		(property "Footprint" "antmicro-footprints:C_0402_1005Metric"
			(at 242.57 50.8 0)
			(effects
				(font
					(size 1.27 1.27)
					(thickness 0.15)
				)
				(justify left bottom)
				(hide yes)
			)
		)
		(property "Datasheet" "https://www.murata.com/products/productdetail?partno=GRM155R61E105KE11%23"
			(at 245.11 50.8 0)
			(effects
				(font
					(size 1.27 1.27)
					(thickness 0.15)
				)
				(justify left bottom)
				(hide yes)
			)
		)
		(property "Description" "SMD Multilayer Ceramic Capacitor, 1 µF, 25 V, 0402 [1005 Metric], ± 10%, X5R, GRM Series"
			(at 262.89 50.8 0)
			(effects
				(font
					(size 1.27 1.27)
				)
				(justify left bottom)
				(hide yes)
			)
		)
		(property "MPN" "GRM155R61E105KE11J"
			(at 247.65 50.8 0)
			(effects
				(font
					(size 1.27 1.27)
					(thickness 0.15)
				)
				(justify left bottom)
				(hide yes)
			)
		)
		(property "Manufacturer" "Murata"
			(at 250.19 50.8 0)
			(effects
				(font
					(size 1.27 1.27)
					(thickness 0.15)
				)
				(justify left bottom)
				(hide yes)
			)
		)
		(property "License" "Apache-2.0"
			(at 252.73 50.8 0)
			(effects
				(font
					(size 1.27 1.27)
					(thickness 0.15)
				)
				(justify left bottom)
				(hide yes)
			)
		)
		(property "Author" "Antmicro"
			(at 255.27 50.8 0)
			(effects
				(font
					(size 1.27 1.27)
					(thickness 0.15)
				)
				(justify left bottom)
				(hide yes)
			)
		)
		(property "Val" "1u"
			(at 231.648 69.85 90)
			(effects
				(font
					(size 1.27 1.27)
					(thickness 0.15)
				)
				(justify right)
			)
		)
		(property "Voltage" "25V"
			(at 257.81 50.8 0)
			(effects
				(font
					(size 1.27 1.27)
				)
				(justify left bottom)
				(hide yes)
			)
		)
		(property "Dielectric" "X5R"
			(at 260.35 50.8 0)
			(effects
				(font
					(size 1.27 1.27)
				)
				(justify left bottom)
				(hide yes)
			)
		)
		(pin "2"
		)
		(pin "1"
		)
		(instances
			(project "thunderbolt-to-10gbe-adapter"
				(path ""
					(reference "C18")
					(unit 1)
				)
			)
		)
	)
	(symbol
		(lib_id "antmicroResistors0402:R_100k_0402")
		(at 175.26 72.39 0)
		(mirror x)
		(unit 1)
		(exclude_from_sim no)
		(in_bom yes)
		(on_board yes)
		(dnp no)
		(property "Reference" "R20"
			(at 175.006 74.676 0)
			(effects
				(font
					(size 1.27 1.27)
					(thickness 0.15)
				)
			)
		)
		(property "Value" "R_100k_0402"
			(at 195.58 59.69 0)
			(effects
				(font
					(size 1.27 1.27)
					(thickness 0.15)
				)
				(justify left bottom)
				(hide yes)
			)
		)
		(property "Footprint" "antmicro-footprints:R_0402_1005Metric"
			(at 195.58 57.15 0)
			(effects
				(font
					(size 1.27 1.27)
					(thickness 0.15)
				)
				(justify left bottom)
				(hide yes)
			)
		)
		(property "Datasheet" "https://www.bourns.com/docs/product-datasheets/cr.pdf"
			(at 195.58 54.61 0)
			(effects
				(font
					(size 1.27 1.27)
					(thickness 0.15)
				)
				(justify left bottom)
				(hide yes)
			)
		)
		(property "Description" "SMD Chip Resistor, 100 kohm, ± 1%, 62.5 mW, 0402 [1005 Metric], Thick Film, General Purpose"
			(at 175.26 72.39 0)
			(effects
				(font
					(size 1.27 1.27)
				)
				(hide yes)
			)
		)
		(property "MPN" "CR0402-FX-1003GLF"
			(at 195.58 52.07 0)
			(effects
				(font
					(size 1.27 1.27)
					(thickness 0.15)
				)
				(justify left bottom)
				(hide yes)
			)
		)
		(property "Manufacturer" "Bourns"
			(at 195.58 49.53 0)
			(effects
				(font
					(size 1.27 1.27)
					(thickness 0.15)
				)
				(justify left bottom)
				(hide yes)
			)
		)
		(property "License" "Apache-2.0"
			(at 195.58 46.99 0)
			(effects
				(font
					(size 1.27 1.27)
					(thickness 0.15)
				)
				(justify left bottom)
				(hide yes)
			)
		)
		(property "Val" "100k"
			(at 179.832 74.676 0)
			(effects
				(font
					(size 1.27 1.27)
					(thickness 0.15)
				)
			)
		)
		(property "Tolerance" "1%"
			(at 195.58 62.23 0)
			(effects
				(font
					(size 1.27 1.27)
				)
				(justify left bottom)
				(hide yes)
			)
		)
		(property "Author" "Antmicro"
			(at 195.58 44.45 0)
			(effects
				(font
					(size 1.27 1.27)
					(thickness 0.15)
				)
				(justify left bottom)
				(hide yes)
			)
		)
		(pin "1"
		)
		(pin "2"
		)
		(instances
			(project "thunderbolt-to-10gbe-adapter"
				(path ""
					(reference "R20")
					(unit 1)
				)
			)
		)
	)
	(symbol
		(lib_id "antmicroCapacitors0402:C_220n_0402")
		(at 176.53 57.15 0)
		(unit 1)
		(exclude_from_sim no)
		(in_bom yes)
		(on_board yes)
		(dnp no)
		(fields_autoplaced yes)
		(property "Reference" "C16"
			(at 179.0763 50.8 0)
			(effects
				(font
					(size 1.27 1.27)
					(thickness 0.15)
				)
			)
		)
		(property "Value" "C_220n_0402"
			(at 196.85 67.31 0)
			(effects
				(font
					(size 1.27 1.27)
					(thickness 0.15)
				)
				(justify left bottom)
				(hide yes)
			)
		)
		(property "Footprint" "antmicro-footprints:C_0402_1005Metric"
			(at 196.85 69.85 0)
			(effects
				(font
					(size 1.27 1.27)
					(thickness 0.15)
				)
				(justify left bottom)
				(hide yes)
			)
		)
		(property "Datasheet" "https://www.yageo.com/en/Chart/Download/pdf/CC0402KRX5R6BB224"
			(at 196.85 72.39 0)
			(effects
				(font
					(size 1.27 1.27)
					(thickness 0.15)
				)
				(justify left bottom)
				(hide yes)
			)
		)
		(property "Description" "SMD Multilayer Ceramic Capacitor, 0.22 µF, 10 V, 0402 [1005 Metric], ± 10%, X5R, CC Series"
			(at 176.53 57.15 0)
			(effects
				(font
					(size 1.27 1.27)
				)
				(hide yes)
			)
		)
		(property "MPN" "CC0402KRX5R6BB224"
			(at 196.85 74.93 0)
			(effects
				(font
					(size 1.27 1.27)
					(thickness 0.15)
				)
				(justify left bottom)
				(hide yes)
			)
		)
		(property "Manufacturer" "YAGEO"
			(at 196.85 77.47 0)
			(effects
				(font
					(size 1.27 1.27)
					(thickness 0.15)
				)
				(justify left bottom)
				(hide yes)
			)
		)
		(property "License" "Apache-2.0"
			(at 196.85 80.01 0)
			(effects
				(font
					(size 1.27 1.27)
					(thickness 0.15)
				)
				(justify left bottom)
				(hide yes)
			)
		)
		(property "Val" "220n"
			(at 179.0763 53.34 0)
			(effects
				(font
					(size 1.27 1.27)
					(thickness 0.15)
				)
			)
		)
		(property "Voltage" ""
			(at 196.85 85.09 0)
			(effects
				(font
					(size 1.27 1.27)
				)
				(justify left bottom)
				(hide yes)
			)
		)
		(property "Dielectric" ""
			(at 196.85 87.63 0)
			(effects
				(font
					(size 1.27 1.27)
				)
				(justify left bottom)
				(hide yes)
			)
		)
		(property "Author" "Antmicro"
			(at 196.85 82.55 0)
			(effects
				(font
					(size 1.27 1.27)
					(thickness 0.15)
				)
				(justify left bottom)
				(hide yes)
			)
		)
		(pin "1"
		)
		(pin "2"
		)
		(instances
			(project "thunderbolt-to-10gbe-adapter"
				(path ""
					(reference "C16")
					(unit 1)
				)
			)
		)
	)
	(symbol
		(lib_id "antmicroResistors0402:R_3k3_0402")
		(at 168.91 167.64 0)
		(unit 1)
		(exclude_from_sim no)
		(in_bom yes)
		(on_board yes)
		(dnp no)
		(property "Reference" "R13"
			(at 167.64 166.37 0)
			(effects
				(font
					(size 1.27 1.27)
					(thickness 0.15)
				)
			)
		)
		(property "Value" "R_3k3_0402"
			(at 189.23 180.34 0)
			(effects
				(font
					(size 1.27 1.27)
					(thickness 0.15)
				)
				(justify left bottom)
				(hide yes)
			)
		)
		(property "Footprint" "antmicro-footprints:R_0402_1005Metric"
			(at 189.23 182.88 0)
			(effects
				(font
					(size 1.27 1.27)
					(thickness 0.15)
				)
				(justify left bottom)
				(hide yes)
			)
		)
		(property "Datasheet" "https://www.bourns.com/docs/product-datasheets/cr.pdf"
			(at 189.23 185.42 0)
			(effects
				(font
					(size 1.27 1.27)
					(thickness 0.15)
				)
				(justify left bottom)
				(hide yes)
			)
		)
		(property "Description" "SMD Chip Resistor, 3.3 kohm, ± 1%, 63 mW, 0402 [1005 Metric], Thick Film, General Purpose"
			(at 168.91 167.64 0)
			(effects
				(font
					(size 1.27 1.27)
				)
				(hide yes)
			)
		)
		(property "MPN" "CR0402-FX-3301GLF"
			(at 189.23 187.96 0)
			(effects
				(font
					(size 1.27 1.27)
					(thickness 0.15)
				)
				(justify left bottom)
				(hide yes)
			)
		)
		(property "Manufacturer" "Bourns"
			(at 189.23 190.5 0)
			(effects
				(font
					(size 1.27 1.27)
					(thickness 0.15)
				)
				(justify left bottom)
				(hide yes)
			)
		)
		(property "License" "Apache-2.0"
			(at 189.23 193.04 0)
			(effects
				(font
					(size 1.27 1.27)
					(thickness 0.15)
				)
				(justify left bottom)
				(hide yes)
			)
		)
		(property "Val" "3k3"
			(at 175.26 166.37 0)
			(effects
				(font
					(size 1.27 1.27)
					(thickness 0.15)
				)
			)
		)
		(property "Tolerance" "1%"
			(at 189.23 177.8 0)
			(effects
				(font
					(size 1.27 1.27)
				)
				(justify left bottom)
				(hide yes)
			)
		)
		(property "Author" "Antmicro"
			(at 189.23 195.58 0)
			(effects
				(font
					(size 1.27 1.27)
					(thickness 0.15)
				)
				(justify left bottom)
				(hide yes)
			)
		)
		(pin "1"
		)
		(pin "2"
		)
		(instances
			(project "thunderbolt-gpu-adapter"
				(path ""
					(reference "R15")
					(unit 1)
				)
			)
			(project "thunderbolt-to-10gbe-adapter"
				(path ""
					(reference "R13")
					(unit 1)
				)
			)
		)
	)
	(symbol
		(lib_id "antmicroCapacitors0402:C_33p_0402")
		(at 205.74 66.04 90)
		(unit 1)
		(exclude_from_sim no)
		(in_bom yes)
		(on_board yes)
		(dnp no)
		(fields_autoplaced yes)
		(property "Reference" "C17"
			(at 208.28 62.2236 90)
			(effects
				(font
					(size 1.27 1.27)
					(thickness 0.15)
				)
				(justify right)
			)
		)
		(property "Value" "C_33p_0402"
			(at 215.9 45.72 0)
			(effects
				(font
					(size 1.27 1.27)
					(thickness 0.15)
				)
				(justify left bottom)
				(hide yes)
			)
		)
		(property "Footprint" "antmicro-footprints:C_0402_1005Metric"
			(at 218.44 45.72 0)
			(effects
				(font
					(size 1.27 1.27)
					(thickness 0.15)
				)
				(justify left bottom)
				(hide yes)
			)
		)
		(property "Datasheet" "https://spicat.kyocera-avx.com/product/mlcc/chartview/04025A330FAT2A/"
			(at 220.98 45.72 0)
			(effects
				(font
					(size 1.27 1.27)
					(thickness 0.15)
				)
				(justify left bottom)
				(hide yes)
			)
		)
		(property "Description" "SMD Multilayer Ceramic Capacitor, 33 pF, 50 V, 0402 [1005 Metric], ± 5%, C0G / NP0, MC"
			(at 205.74 66.04 0)
			(effects
				(font
					(size 1.27 1.27)
				)
				(hide yes)
			)
		)
		(property "MPN" "04025A330FAT2A"
			(at 223.52 45.72 0)
			(effects
				(font
					(size 1.27 1.27)
					(thickness 0.15)
				)
				(justify left bottom)
				(hide yes)
			)
		)
		(property "Manufacturer" "KYOCERA AVX"
			(at 226.06 45.72 0)
			(effects
				(font
					(size 1.27 1.27)
					(thickness 0.15)
				)
				(justify left bottom)
				(hide yes)
			)
		)
		(property "License" "Apache-2.0"
			(at 228.6 45.72 0)
			(effects
				(font
					(size 1.27 1.27)
					(thickness 0.15)
				)
				(justify left bottom)
				(hide yes)
			)
		)
		(property "Val" "33p"
			(at 208.28 64.7636 90)
			(effects
				(font
					(size 1.27 1.27)
					(thickness 0.15)
				)
				(justify right)
			)
		)
		(property "Voltage" ""
			(at 233.68 45.72 0)
			(effects
				(font
					(size 1.27 1.27)
				)
				(justify left bottom)
				(hide yes)
			)
		)
		(property "Dielectric" ""
			(at 236.22 45.72 0)
			(effects
				(font
					(size 1.27 1.27)
				)
				(justify left bottom)
				(hide yes)
			)
		)
		(property "Author" "Antmicro"
			(at 231.14 45.72 0)
			(effects
				(font
					(size 1.27 1.27)
					(thickness 0.15)
				)
				(justify left bottom)
				(hide yes)
			)
		)
		(pin "1"
		)
		(pin "2"
		)
		(instances
			(project "thunderbolt-to-10gbe-adapter"
				(path ""
					(reference "C17")
					(unit 1)
				)
			)
		)
	)
	(symbol
		(lib_id "antmicroCapacitorsmisc:C_22u_25V_0805")
		(at 267.97 138.43 90)
		(unit 1)
		(exclude_from_sim no)
		(in_bom yes)
		(on_board yes)
		(dnp no)
		(fields_autoplaced yes)
		(property "Reference" "C30"
			(at 270.51 133.3436 90)
			(effects
				(font
					(size 1.27 1.27)
					(thickness 0.15)
				)
				(justify right)
			)
		)
		(property "Value" "C_22u_25V_0805"
			(at 278.13 118.11 0)
			(effects
				(font
					(size 1.27 1.27)
					(thickness 0.15)
				)
				(justify left bottom)
				(hide yes)
			)
		)
		(property "Footprint" "antmicro-footprints:C_0805_2012Metric"
			(at 280.67 118.11 0)
			(effects
				(font
					(size 1.27 1.27)
					(thickness 0.15)
				)
				(justify left bottom)
				(hide yes)
			)
		)
		(property "Datasheet" "https://product.samsungsem.com/mlcc/CL21A226MAYNNN.do"
			(at 283.21 118.11 0)
			(effects
				(font
					(size 1.27 1.27)
					(thickness 0.15)
				)
				(justify left bottom)
				(hide yes)
			)
		)
		(property "Description" "SMT Multilayer Ceramic Capacitor, 22uF, +/-20%, 25V, X5R, 0805 [2012 Metric]"
			(at 267.97 138.43 0)
			(effects
				(font
					(size 1.27 1.27)
				)
				(hide yes)
			)
		)
		(property "MPN" "CL21A226MAYNNNE"
			(at 285.75 118.11 0)
			(effects
				(font
					(size 1.27 1.27)
					(thickness 0.15)
				)
				(justify left bottom)
				(hide yes)
			)
		)
		(property "Manufacturer" "Samsung Electro-Mechanics"
			(at 288.29 118.11 0)
			(effects
				(font
					(size 1.27 1.27)
					(thickness 0.15)
				)
				(justify left bottom)
				(hide yes)
			)
		)
		(property "License" "Apache-2.0"
			(at 290.83 118.11 0)
			(effects
				(font
					(size 1.27 1.27)
					(thickness 0.15)
				)
				(justify left bottom)
				(hide yes)
			)
		)
		(property "Val" "22u"
			(at 270.51 135.8836 90)
			(effects
				(font
					(size 1.27 1.27)
					(thickness 0.15)
				)
				(justify right)
			)
		)
		(property "Voltage" "25V"
			(at 270.51 138.4236 90)
			(effects
				(font
					(size 1.27 1.27)
				)
				(justify right)
			)
		)
		(property "Dielectric" "X5R"
			(at 298.45 118.11 0)
			(effects
				(font
					(size 1.27 1.27)
				)
				(justify left bottom)
				(hide yes)
			)
		)
		(property "Author" "Antmicro"
			(at 293.37 118.11 0)
			(effects
				(font
					(size 1.27 1.27)
					(thickness 0.15)
				)
				(justify left bottom)
				(hide yes)
			)
		)
		(property "Public" "False"
			(at 300.99 118.11 0)
			(effects
				(font
					(size 1.27 1.27)
				)
				(justify left bottom)
				(hide yes)
			)
		)
		(pin "1"
		)
		(pin "2"
		)
		(instances
			(project "thunderbolt-gpu-adapter"
				(path ""
					(reference "C48")
					(unit 1)
				)
			)
			(project "thunderbolt-to-10gbe-adapter"
				(path ""
					(reference "C30")
					(unit 1)
				)
			)
		)
	)
	(symbol
		(lib_id "antmicroResistors0402:R_10k_0402")
		(at 168.91 193.04 0)
		(unit 1)
		(exclude_from_sim no)
		(in_bom yes)
		(on_board yes)
		(dnp no)
		(property "Reference" "R18"
			(at 171.45 194.945 0)
			(effects
				(font
					(size 1.27 1.27)
					(thickness 0.15)
				)
			)
		)
		(property "Value" "R_10k_0402"
			(at 189.23 205.74 0)
			(effects
				(font
					(size 1.27 1.27)
					(thickness 0.15)
				)
				(justify left bottom)
				(hide yes)
			)
		)
		(property "Footprint" "antmicro-footprints:R_0402_1005Metric"
			(at 189.23 208.28 0)
			(effects
				(font
					(size 1.27 1.27)
					(thickness 0.15)
				)
				(justify left bottom)
				(hide yes)
			)
		)
		(property "Datasheet" "https://www.bourns.com/docs/product-datasheets/cr.pdf"
			(at 189.23 210.82 0)
			(effects
				(font
					(size 1.27 1.27)
					(thickness 0.15)
				)
				(justify left bottom)
				(hide yes)
			)
		)
		(property "Description" "SMD Chip Resistor, 10 kohm, ± 1%, 62.5 mW, 0402 [1005 Metric], Thick Film, General Purpose"
			(at 168.91 193.04 0)
			(effects
				(font
					(size 1.27 1.27)
				)
				(hide yes)
			)
		)
		(property "MPN" "CR0402-FX-1002GLF"
			(at 189.23 213.36 0)
			(effects
				(font
					(size 1.27 1.27)
					(thickness 0.15)
				)
				(justify left bottom)
				(hide yes)
			)
		)
		(property "Manufacturer" "Bourns"
			(at 189.23 215.9 0)
			(effects
				(font
					(size 1.27 1.27)
					(thickness 0.15)
				)
				(justify left bottom)
				(hide yes)
			)
		)
		(property "License" "Apache-2.0"
			(at 189.23 218.44 0)
			(effects
				(font
					(size 1.27 1.27)
					(thickness 0.15)
				)
				(justify left bottom)
				(hide yes)
			)
		)
		(property "Val" "10k"
			(at 171.45 193.04 0)
			(effects
				(font
					(size 1.27 1.27)
					(thickness 0.15)
				)
			)
		)
		(property "Tolerance" "1%"
			(at 189.23 203.2 0)
			(effects
				(font
					(size 1.27 1.27)
				)
				(justify left bottom)
				(hide yes)
			)
		)
		(property "Author" "Antmicro"
			(at 189.23 220.98 0)
			(effects
				(font
					(size 1.27 1.27)
					(thickness 0.15)
				)
				(justify left bottom)
				(hide yes)
			)
		)
		(pin "1"
		)
		(pin "2"
		)
		(instances
			(project "thunderbolt-gpu-adapter"
				(path ""
					(reference "R20")
					(unit 1)
				)
			)
			(project "thunderbolt-to-10gbe-adapter"
				(path ""
					(reference "R18")
					(unit 1)
				)
			)
		)
	)
	(symbol
		(lib_id "antmicroResistors0402:R_100k_0402")
		(at 107.95 232.41 270)
		(mirror x)
		(unit 1)
		(exclude_from_sim no)
		(in_bom yes)
		(on_board yes)
		(dnp no)
		(fields_autoplaced yes)
		(property "Reference" "R4"
			(at 105.41 228.6 90)
			(effects
				(font
					(size 1.27 1.27)
					(thickness 0.15)
				)
				(justify right)
			)
		)
		(property "Value" "R_100k_0402"
			(at 95.25 212.09 0)
			(effects
				(font
					(size 1.27 1.27)
					(thickness 0.15)
				)
				(justify left bottom)
				(hide yes)
			)
		)
		(property "Footprint" "antmicro-footprints:R_0402_1005Metric"
			(at 92.71 212.09 0)
			(effects
				(font
					(size 1.27 1.27)
					(thickness 0.15)
				)
				(justify left bottom)
				(hide yes)
			)
		)
		(property "Datasheet" "https://www.bourns.com/docs/product-datasheets/cr.pdf"
			(at 90.17 212.09 0)
			(effects
				(font
					(size 1.27 1.27)
					(thickness 0.15)
				)
				(justify left bottom)
				(hide yes)
			)
		)
		(property "Description" "SMD Chip Resistor, 100 kohm, ± 1%, 62.5 mW, 0402 [1005 Metric], Thick Film, General Purpose"
			(at 107.95 232.41 0)
			(effects
				(font
					(size 1.27 1.27)
				)
				(hide yes)
			)
		)
		(property "MPN" "CR0402-FX-1003GLF"
			(at 87.63 212.09 0)
			(effects
				(font
					(size 1.27 1.27)
					(thickness 0.15)
				)
				(justify left bottom)
				(hide yes)
			)
		)
		(property "Manufacturer" "Bourns"
			(at 85.09 212.09 0)
			(effects
				(font
					(size 1.27 1.27)
					(thickness 0.15)
				)
				(justify left bottom)
				(hide yes)
			)
		)
		(property "License" "Apache-2.0"
			(at 82.55 212.09 0)
			(effects
				(font
					(size 1.27 1.27)
					(thickness 0.15)
				)
				(justify left bottom)
				(hide yes)
			)
		)
		(property "Val" "100k"
			(at 105.41 231.14 90)
			(effects
				(font
					(size 1.27 1.27)
					(thickness 0.15)
				)
				(justify right)
			)
		)
		(property "Tolerance" "1%"
			(at 97.79 212.09 0)
			(effects
				(font
					(size 1.27 1.27)
				)
				(justify left bottom)
				(hide yes)
			)
		)
		(property "Author" "Antmicro"
			(at 80.01 212.09 0)
			(effects
				(font
					(size 1.27 1.27)
					(thickness 0.15)
				)
				(justify left bottom)
				(hide yes)
			)
		)
		(pin "1"
		)
		(pin "2"
		)
		(instances
			(project "thunderbolt-gpu-adapter"
				(path ""
					(reference "R10")
					(unit 1)
				)
			)
			(project "thunderbolt-to-10gbe-adapter"
				(path ""
					(reference "R4")
					(unit 1)
				)
			)
		)
	)
	(symbol
		(lib_id "antmicropower:GND")
		(at 147.32 193.04 0)
		(unit 1)
		(exclude_from_sim no)
		(in_bom yes)
		(on_board yes)
		(dnp no)
		(property "Reference" "#PWR024"
			(at 147.32 199.39 0)
			(effects
				(font
					(size 1.27 1.27)
				)
				(hide yes)
			)
		)
		(property "Value" "GND"
			(at 147.32 196.85 0)
			(effects
				(font
					(size 1.27 1.27)
				)
			)
		)
		(property "Footprint" ""
			(at 147.32 193.04 0)
			(effects
				(font
					(size 1.27 1.27)
				)
				(hide yes)
			)
		)
		(property "Datasheet" ""
			(at 147.32 193.04 0)
			(effects
				(font
					(size 1.27 1.27)
				)
				(hide yes)
			)
		)
		(property "Description" ""
			(at 147.32 193.04 0)
			(effects
				(font
					(size 1.27 1.27)
				)
				(hide yes)
			)
		)
		(property "Author" "Antmicro"
			(at 156.21 200.66 0)
			(effects
				(font
					(size 1.27 1.27)
					(thickness 0.15)
				)
				(justify left bottom)
				(hide yes)
			)
		)
		(property "License" "Apache-2.0"
			(at 156.21 203.2 0)
			(effects
				(font
					(size 1.27 1.27)
					(thickness 0.15)
				)
				(justify left bottom)
				(hide yes)
			)
		)
		(pin "1"
		)
		(instances
			(project "thunderbolt-gpu-adapter"
				(path ""
					(reference "#PWR021")
					(unit 1)
				)
			)
			(project "thunderbolt-to-10gbe-adapter"
				(path ""
					(reference "#PWR024")
					(unit 1)
				)
			)
		)
	)
	(symbol
		(lib_id "antmicroCapacitors0402:C_4u7_25V_0402")
		(at 157.48 134.62 0)
		(unit 1)
		(exclude_from_sim no)
		(in_bom yes)
		(on_board yes)
		(dnp no)
		(fields_autoplaced yes)
		(property "Reference" "C13"
			(at 157.48 133.35 0)
			(effects
				(font
					(size 1.27 1.27)
					(thickness 0.15)
				)
			)
		)
		(property "Value" "C_4u7_25V_0402"
			(at 177.8 144.78 0)
			(effects
				(font
					(size 1.27 1.27)
					(thickness 0.15)
				)
				(justify left bottom)
				(hide yes)
			)
		)
		(property "Footprint" "antmicro-footprints:C_0402_1005Metric"
			(at 177.8 147.32 0)
			(effects
				(font
					(size 1.27 1.27)
					(thickness 0.15)
				)
				(justify left bottom)
				(hide yes)
			)
		)
		(property "Datasheet" "https://www.murata.com/products/productdetail?partno=GRM155C61E475ME15%23"
			(at 177.8 149.86 0)
			(effects
				(font
					(size 1.27 1.27)
					(thickness 0.15)
				)
				(justify left bottom)
				(hide yes)
			)
		)
		(property "Description" "SMD Multilayer Ceramic Capacitor"
			(at 157.48 134.62 0)
			(effects
				(font
					(size 1.27 1.27)
				)
				(hide yes)
			)
		)
		(property "MPN" "GRM155C61E475ME15J"
			(at 177.8 152.4 0)
			(effects
				(font
					(size 1.27 1.27)
					(thickness 0.15)
				)
				(justify left bottom)
				(hide yes)
			)
		)
		(property "Manufacturer" "Murata"
			(at 177.8 154.94 0)
			(effects
				(font
					(size 1.27 1.27)
					(thickness 0.15)
				)
				(justify left bottom)
				(hide yes)
			)
		)
		(property "License" "Apache-2.0"
			(at 177.8 157.48 0)
			(effects
				(font
					(size 1.27 1.27)
					(thickness 0.15)
				)
				(justify left bottom)
				(hide yes)
			)
		)
		(property "Val" "4u7"
			(at 162.56 133.35 0)
			(effects
				(font
					(size 1.27 1.27)
					(thickness 0.15)
				)
			)
		)
		(property "Voltage" "25V"
			(at 161.29 134.62 0)
			(effects
				(font
					(size 1.27 1.27)
				)
				(justify left bottom)
				(hide yes)
			)
		)
		(property "Dielectric" "X5S"
			(at 177.8 165.1 0)
			(effects
				(font
					(size 1.27 1.27)
				)
				(justify left bottom)
				(hide yes)
			)
		)
		(property "Author" "Antmicro"
			(at 177.8 160.02 0)
			(effects
				(font
					(size 1.27 1.27)
					(thickness 0.15)
				)
				(justify left bottom)
				(hide yes)
			)
		)
		(pin "1"
		)
		(pin "2"
		)
		(instances
			(project "thunderbolt-to-10gbe-adapter"
				(path ""
					(reference "C13")
					(unit 1)
				)
			)
		)
	)
	(symbol
		(lib_id "antmicroTestPoints:TP_0.75mm_SMD")
		(at 289.56 63.5 0)
		(unit 1)
		(exclude_from_sim no)
		(in_bom no)
		(on_board yes)
		(dnp no)
		(fields_autoplaced yes)
		(property "Reference" "TP3"
			(at 294.64 63.5 0)
			(effects
				(font
					(size 1.27 1.27)
					(thickness 0.15)
				)
				(justify left)
			)
		)
		(property "Value" "TP_0.75mm_SMD"
			(at 299.72 67.31 0)
			(effects
				(font
					(size 1.27 1.27)
					(thickness 0.15)
				)
				(justify left bottom)
				(hide yes)
			)
		)
		(property "Footprint" "antmicro-footprints:TP_SMD_0.75mm"
			(at 299.72 69.85 0)
			(effects
				(font
					(size 1.27 1.27)
					(thickness 0.15)
				)
				(justify left bottom)
				(hide yes)
			)
		)
		(property "Datasheet" ""
			(at 307.34 76.2 0)
			(effects
				(font
					(size 1.27 1.27)
					(thickness 0.15)
				)
				(justify left bottom)
				(hide yes)
			)
		)
		(property "Description" "SMT test point"
			(at 300.355 77.47 0)
			(effects
				(font
					(size 1.27 1.27)
				)
				(justify left bottom)
				(hide yes)
			)
		)
		(property "License" "Apache-2.0"
			(at 299.72 74.93 0)
			(effects
				(font
					(size 1.27 1.27)
					(thickness 0.15)
				)
				(justify left bottom)
				(hide yes)
			)
		)
		(property "Manufacturer" ""
			(at 300.355 69.85 0)
			(effects
				(font
					(size 1.27 1.27)
					(thickness 0.15)
				)
				(justify left bottom)
				(hide yes)
			)
		)
		(property "MPN" ""
			(at 300.355 74.93 0)
			(effects
				(font
					(size 1.27 1.27)
					(thickness 0.15)
				)
				(justify left bottom)
				(hide yes)
			)
		)
		(property "Author" "Antmicro"
			(at 299.72 72.39 0)
			(effects
				(font
					(size 1.27 1.27)
					(thickness 0.15)
				)
				(justify left bottom)
				(hide yes)
			)
		)
		(pin "1"
		)
		(instances
			(project "thunderbolt-to-10gbe-adapter"
				(path ""
					(reference "TP3")
					(unit 1)
				)
			)
		)
	)
	(symbol
		(lib_id "antmicropower:GND")
		(at 240.03 77.47 0)
		(unit 1)
		(exclude_from_sim no)
		(in_bom yes)
		(on_board yes)
		(dnp no)
		(fields_autoplaced yes)
		(property "Reference" "#PWR034"
			(at 240.03 83.82 0)
			(effects
				(font
					(size 1.27 1.27)
				)
				(hide yes)
			)
		)
		(property "Value" "GND"
			(at 240.03 81.28 0)
			(effects
				(font
					(size 1.27 1.27)
				)
			)
		)
		(property "Footprint" ""
			(at 240.03 77.47 0)
			(effects
				(font
					(size 1.27 1.27)
				)
				(hide yes)
			)
		)
		(property "Datasheet" ""
			(at 240.03 77.47 0)
			(effects
				(font
					(size 1.27 1.27)
				)
				(hide yes)
			)
		)
		(property "Description" ""
			(at 240.03 77.47 0)
			(effects
				(font
					(size 1.27 1.27)
				)
				(hide yes)
			)
		)
		(property "Author" "Antmicro"
			(at 248.92 85.09 0)
			(effects
				(font
					(size 1.27 1.27)
					(thickness 0.15)
				)
				(justify left bottom)
				(hide yes)
			)
		)
		(property "License" "Apache-2.0"
			(at 248.92 87.63 0)
			(effects
				(font
					(size 1.27 1.27)
					(thickness 0.15)
				)
				(justify left bottom)
				(hide yes)
			)
		)
		(pin "1"
		)
		(instances
			(project "thunderbolt-to-10gbe-adapter"
				(path ""
					(reference "#PWR034")
					(unit 1)
				)
			)
		)
	)
	(symbol
		(lib_id "antmicroResistors0402:R_10k_0402")
		(at 132.08 151.13 90)
		(unit 1)
		(exclude_from_sim no)
		(in_bom yes)
		(on_board yes)
		(dnp no)
		(property "Reference" "R8"
			(at 133.35 147.32 90)
			(effects
				(font
					(size 1.27 1.27)
					(thickness 0.15)
				)
				(justify right)
			)
		)
		(property "Value" "R_10k_0402"
			(at 144.78 130.81 0)
			(effects
				(font
					(size 1.27 1.27)
					(thickness 0.15)
				)
				(justify left bottom)
				(hide yes)
			)
		)
		(property "Footprint" "antmicro-footprints:R_0402_1005Metric"
			(at 147.32 130.81 0)
			(effects
				(font
					(size 1.27 1.27)
					(thickness 0.15)
				)
				(justify left bottom)
				(hide yes)
			)
		)
		(property "Datasheet" "https://www.bourns.com/docs/product-datasheets/cr.pdf"
			(at 149.86 130.81 0)
			(effects
				(font
					(size 1.27 1.27)
					(thickness 0.15)
				)
				(justify left bottom)
				(hide yes)
			)
		)
		(property "Description" "SMD Chip Resistor, 10 kohm, ± 1%, 62.5 mW, 0402 [1005 Metric], Thick Film, General Purpose"
			(at 132.08 151.13 0)
			(effects
				(font
					(size 1.27 1.27)
				)
				(hide yes)
			)
		)
		(property "MPN" "CR0402-FX-1002GLF"
			(at 152.4 130.81 0)
			(effects
				(font
					(size 1.27 1.27)
					(thickness 0.15)
				)
				(justify left bottom)
				(hide yes)
			)
		)
		(property "Manufacturer" "Bourns"
			(at 154.94 130.81 0)
			(effects
				(font
					(size 1.27 1.27)
					(thickness 0.15)
				)
				(justify left bottom)
				(hide yes)
			)
		)
		(property "License" "Apache-2.0"
			(at 157.48 130.81 0)
			(effects
				(font
					(size 1.27 1.27)
					(thickness 0.15)
				)
				(justify left bottom)
				(hide yes)
			)
		)
		(property "Val" "10k"
			(at 133.35 149.86 90)
			(effects
				(font
					(size 1.27 1.27)
					(thickness 0.15)
				)
				(justify right)
			)
		)
		(property "Tolerance" "1%"
			(at 142.24 130.81 0)
			(effects
				(font
					(size 1.27 1.27)
				)
				(justify left bottom)
				(hide yes)
			)
		)
		(property "Author" "Antmicro"
			(at 160.02 130.81 0)
			(effects
				(font
					(size 1.27 1.27)
					(thickness 0.15)
				)
				(justify left bottom)
				(hide yes)
			)
		)
		(pin "1"
		)
		(pin "2"
		)
		(instances
			(project "thunderbolt-gpu-adapter"
				(path ""
					(reference "R2")
					(unit 1)
				)
			)
			(project "thunderbolt-to-10gbe-adapter"
				(path ""
					(reference "R8")
					(unit 1)
				)
			)
		)
	)
	(symbol
		(lib_id "antmicropower:GND")
		(at 214.63 77.47 0)
		(unit 1)
		(exclude_from_sim no)
		(in_bom yes)
		(on_board yes)
		(dnp no)
		(fields_autoplaced yes)
		(property "Reference" "#PWR031"
			(at 214.63 83.82 0)
			(effects
				(font
					(size 1.27 1.27)
				)
				(hide yes)
			)
		)
		(property "Value" "GND"
			(at 214.63 81.28 0)
			(effects
				(font
					(size 1.27 1.27)
				)
			)
		)
		(property "Footprint" ""
			(at 214.63 77.47 0)
			(effects
				(font
					(size 1.27 1.27)
				)
				(hide yes)
			)
		)
		(property "Datasheet" ""
			(at 214.63 77.47 0)
			(effects
				(font
					(size 1.27 1.27)
				)
				(hide yes)
			)
		)
		(property "Description" ""
			(at 214.63 77.47 0)
			(effects
				(font
					(size 1.27 1.27)
				)
				(hide yes)
			)
		)
		(property "Author" "Antmicro"
			(at 223.52 85.09 0)
			(effects
				(font
					(size 1.27 1.27)
					(thickness 0.15)
				)
				(justify left bottom)
				(hide yes)
			)
		)
		(property "License" "Apache-2.0"
			(at 223.52 87.63 0)
			(effects
				(font
					(size 1.27 1.27)
					(thickness 0.15)
				)
				(justify left bottom)
				(hide yes)
			)
		)
		(pin "1"
		)
		(instances
			(project "thunderbolt-to-10gbe-adapter"
				(path ""
					(reference "#PWR031")
					(unit 1)
				)
			)
		)
	)
	(symbol
		(lib_id "antmicroCapacitors0402:C_100n_0402")
		(at 147.32 50.8 90)
		(unit 1)
		(exclude_from_sim no)
		(in_bom yes)
		(on_board yes)
		(dnp no)
		(fields_autoplaced yes)
		(property "Reference" "C10"
			(at 149.86 46.9836 90)
			(effects
				(font
					(size 1.27 1.27)
					(thickness 0.15)
				)
				(justify right)
			)
		)
		(property "Value" "C_100n_0402"
			(at 157.48 30.48 0)
			(effects
				(font
					(size 1.27 1.27)
					(thickness 0.15)
				)
				(justify left bottom)
				(hide yes)
			)
		)
		(property "Footprint" "antmicro-footprints:C_0402_1005Metric"
			(at 160.02 30.48 0)
			(effects
				(font
					(size 1.27 1.27)
					(thickness 0.15)
				)
				(justify left bottom)
				(hide yes)
			)
		)
		(property "Datasheet" "https://www.murata.com/products/productdetail?partno=GRM155R61H104KE14%23"
			(at 162.56 30.48 0)
			(effects
				(font
					(size 1.27 1.27)
					(thickness 0.15)
				)
				(justify left bottom)
				(hide yes)
			)
		)
		(property "Description" "SMD Multilayer Ceramic Capacitor, 0.1 µF, 50 V, 0402 [1005 Metric], ± 10%, X5R, GRM Series"
			(at 147.32 50.8 0)
			(effects
				(font
					(size 1.27 1.27)
				)
				(hide yes)
			)
		)
		(property "MPN" "GRM155R61H104KE14D"
			(at 165.1 30.48 0)
			(effects
				(font
					(size 1.27 1.27)
					(thickness 0.15)
				)
				(justify left bottom)
				(hide yes)
			)
		)
		(property "Manufacturer" "Murata"
			(at 167.64 30.48 0)
			(effects
				(font
					(size 1.27 1.27)
					(thickness 0.15)
				)
				(justify left bottom)
				(hide yes)
			)
		)
		(property "License" "Apache-2.0"
			(at 170.18 30.48 0)
			(effects
				(font
					(size 1.27 1.27)
					(thickness 0.15)
				)
				(justify left bottom)
				(hide yes)
			)
		)
		(property "Val" "100n"
			(at 149.86 49.5236 90)
			(effects
				(font
					(size 1.27 1.27)
					(thickness 0.15)
				)
				(justify right)
			)
		)
		(property "Voltage" "50V"
			(at 175.26 30.48 0)
			(effects
				(font
					(size 1.27 1.27)
				)
				(justify left bottom)
				(hide yes)
			)
		)
		(property "Dielectric" "X5R"
			(at 177.8 30.48 0)
			(effects
				(font
					(size 1.27 1.27)
				)
				(justify left bottom)
				(hide yes)
			)
		)
		(property "Author" "Antmicro"
			(at 172.72 30.48 0)
			(effects
				(font
					(size 1.27 1.27)
					(thickness 0.15)
				)
				(justify left bottom)
				(hide yes)
			)
		)
		(pin "1"
		)
		(pin "2"
		)
		(instances
			(project "thunderbolt-to-10gbe-adapter"
				(path ""
					(reference "C10")
					(unit 1)
				)
			)
		)
	)
	(symbol
		(lib_id "antmicroResistors0402:R_100k_0402")
		(at 109.22 245.11 90)
		(unit 1)
		(exclude_from_sim no)
		(in_bom yes)
		(on_board yes)
		(dnp no)
		(fields_autoplaced yes)
		(property "Reference" "R5"
			(at 106.68 241.3 90)
			(effects
				(font
					(size 1.27 1.27)
					(thickness 0.15)
				)
				(justify left)
			)
		)
		(property "Value" "R_100k_0402"
			(at 121.92 224.79 0)
			(effects
				(font
					(size 1.27 1.27)
					(thickness 0.15)
				)
				(justify left bottom)
				(hide yes)
			)
		)
		(property "Footprint" "antmicro-footprints:R_0402_1005Metric"
			(at 124.46 224.79 0)
			(effects
				(font
					(size 1.27 1.27)
					(thickness 0.15)
				)
				(justify left bottom)
				(hide yes)
			)
		)
		(property "Datasheet" "https://www.bourns.com/docs/product-datasheets/cr.pdf"
			(at 127 224.79 0)
			(effects
				(font
					(size 1.27 1.27)
					(thickness 0.15)
				)
				(justify left bottom)
				(hide yes)
			)
		)
		(property "Description" "SMD Chip Resistor, 100 kohm, ± 1%, 62.5 mW, 0402 [1005 Metric], Thick Film, General Purpose"
			(at 109.22 245.11 0)
			(effects
				(font
					(size 1.27 1.27)
				)
				(hide yes)
			)
		)
		(property "MPN" "CR0402-FX-1003GLF"
			(at 129.54 224.79 0)
			(effects
				(font
					(size 1.27 1.27)
					(thickness 0.15)
				)
				(justify left bottom)
				(hide yes)
			)
		)
		(property "Manufacturer" "Bourns"
			(at 132.08 224.79 0)
			(effects
				(font
					(size 1.27 1.27)
					(thickness 0.15)
				)
				(justify left bottom)
				(hide yes)
			)
		)
		(property "License" "Apache-2.0"
			(at 134.62 224.79 0)
			(effects
				(font
					(size 1.27 1.27)
					(thickness 0.15)
				)
				(justify left bottom)
				(hide yes)
			)
		)
		(property "Val" "100k"
			(at 106.68 243.84 90)
			(effects
				(font
					(size 1.27 1.27)
					(thickness 0.15)
				)
				(justify left)
			)
		)
		(property "Tolerance" "1%"
			(at 119.38 224.79 0)
			(effects
				(font
					(size 1.27 1.27)
				)
				(justify left bottom)
				(hide yes)
			)
		)
		(property "Author" "Antmicro"
			(at 137.16 224.79 0)
			(effects
				(font
					(size 1.27 1.27)
					(thickness 0.15)
				)
				(justify left bottom)
				(hide yes)
			)
		)
		(pin "1"
		)
		(pin "2"
		)
		(instances
			(project "thunderbolt-gpu-adapter"
				(path ""
					(reference "R9")
					(unit 1)
				)
			)
			(project "thunderbolt-to-10gbe-adapter"
				(path ""
					(reference "R5")
					(unit 1)
				)
			)
		)
	)
	(symbol
		(lib_id "antmicropower:+5V")
		(at 283.21 128.27 0)
		(unit 1)
		(exclude_from_sim no)
		(in_bom yes)
		(on_board yes)
		(dnp no)
		(property "Reference" "#PWR054"
			(at 298.45 130.81 0)
			(effects
				(font
					(size 1.27 1.27)
					(thickness 0.15)
				)
				(justify left bottom)
				(hide yes)
			)
		)
		(property "Value" "+5V_USB"
			(at 283.21 124.46 0)
			(effects
				(font
					(size 1.27 1.27)
					(thickness 0.15)
				)
			)
		)
		(property "Footprint" ""
			(at 298.45 135.89 0)
			(effects
				(font
					(size 1.27 1.27)
					(thickness 0.15)
				)
				(justify left bottom)
				(hide yes)
			)
		)
		(property "Datasheet" ""
			(at 298.45 138.43 0)
			(effects
				(font
					(size 1.27 1.27)
					(thickness 0.15)
				)
				(justify left bottom)
				(hide yes)
			)
		)
		(property "Description" ""
			(at 298.45 140.97 0)
			(effects
				(font
					(size 1.27 1.27)
				)
				(justify left bottom)
				(hide yes)
			)
		)
		(property "Author" "Antmicro"
			(at 298.45 135.89 0)
			(effects
				(font
					(size 1.27 1.27)
					(thickness 0.15)
				)
				(justify left bottom)
				(hide yes)
			)
		)
		(property "License" "Apache-2.0"
			(at 298.45 138.43 0)
			(effects
				(font
					(size 1.27 1.27)
					(thickness 0.15)
				)
				(justify left bottom)
				(hide yes)
			)
		)
		(pin "1"
		)
		(instances
			(project "thunderbolt-to-10gbe-adapter"
				(path ""
					(reference "#PWR054")
					(unit 1)
				)
			)
		)
	)
	(symbol
		(lib_id "antmicroCapacitors0402:C_2u2_0402")
		(at 237.49 152.4 0)
		(unit 1)
		(exclude_from_sim no)
		(in_bom yes)
		(on_board yes)
		(dnp no)
		(property "Reference" "C22"
			(at 242.57 151.13 0)
			(effects
				(font
					(size 1.27 1.27)
					(thickness 0.15)
				)
			)
		)
		(property "Value" "C_2u2_0402"
			(at 257.81 162.56 0)
			(effects
				(font
					(size 1.27 1.27)
					(thickness 0.15)
				)
				(justify left bottom)
				(hide yes)
			)
		)
		(property "Footprint" "antmicro-footprints:C_0402_1005Metric"
			(at 257.81 165.1 0)
			(effects
				(font
					(size 1.27 1.27)
					(thickness 0.15)
				)
				(justify left bottom)
				(hide yes)
			)
		)
		(property "Datasheet" "https://product.tdk.com/en/search/capacitor/ceramic/mlcc/info?part_no=C1005X5R1A225K050BC"
			(at 257.81 167.64 0)
			(effects
				(font
					(size 1.27 1.27)
					(thickness 0.15)
				)
				(justify left bottom)
				(hide yes)
			)
		)
		(property "Description" "SMD Multilayer Ceramic Capacitor, 2.2 µF, 10 V, 0402 [1005 Metric], ± 10%, X5R, C"
			(at 237.49 152.4 0)
			(effects
				(font
					(size 1.27 1.27)
				)
				(hide yes)
			)
		)
		(property "MPN" "C1005X5R1A225K050BC"
			(at 257.81 170.18 0)
			(effects
				(font
					(size 1.27 1.27)
					(thickness 0.15)
				)
				(justify left bottom)
				(hide yes)
			)
		)
		(property "Manufacturer" "TDK"
			(at 257.81 172.72 0)
			(effects
				(font
					(size 1.27 1.27)
					(thickness 0.15)
				)
				(justify left bottom)
				(hide yes)
			)
		)
		(property "License" "Apache-2.0"
			(at 257.81 175.26 0)
			(effects
				(font
					(size 1.27 1.27)
					(thickness 0.15)
				)
				(justify left bottom)
				(hide yes)
			)
		)
		(property "Val" "2u2"
			(at 242.57 153.67 0)
			(effects
				(font
					(size 1.27 1.27)
					(thickness 0.15)
				)
			)
		)
		(property "Voltage" ""
			(at 257.81 180.34 0)
			(effects
				(font
					(size 1.27 1.27)
				)
				(justify left bottom)
				(hide yes)
			)
		)
		(property "Dielectric" ""
			(at 257.81 182.88 0)
			(effects
				(font
					(size 1.27 1.27)
				)
				(justify left bottom)
				(hide yes)
			)
		)
		(property "Author" "Antmicro"
			(at 257.81 177.8 0)
			(effects
				(font
					(size 1.27 1.27)
					(thickness 0.15)
				)
				(justify left bottom)
				(hide yes)
			)
		)
		(pin "1"
		)
		(pin "2"
		)
		(instances
			(project "thunderbolt-gpu-adapter"
				(path ""
					(reference "C37")
					(unit 1)
				)
			)
			(project "thunderbolt-to-10gbe-adapter"
				(path ""
					(reference "C22")
					(unit 1)
				)
			)
		)
	)
	(symbol
		(lib_id "antmicropower:GND")
		(at 241.3 167.64 0)
		(unit 1)
		(exclude_from_sim no)
		(in_bom yes)
		(on_board yes)
		(dnp no)
		(property "Reference" "#PWR035"
			(at 241.3 173.99 0)
			(effects
				(font
					(size 1.27 1.27)
				)
				(hide yes)
			)
		)
		(property "Value" "GND"
			(at 241.3 171.45 0)
			(effects
				(font
					(size 1.27 1.27)
				)
			)
		)
		(property "Footprint" ""
			(at 241.3 167.64 0)
			(effects
				(font
					(size 1.27 1.27)
				)
				(hide yes)
			)
		)
		(property "Datasheet" ""
			(at 241.3 167.64 0)
			(effects
				(font
					(size 1.27 1.27)
				)
				(hide yes)
			)
		)
		(property "Description" ""
			(at 241.3 167.64 0)
			(effects
				(font
					(size 1.27 1.27)
				)
				(hide yes)
			)
		)
		(property "Author" "Antmicro"
			(at 250.19 175.26 0)
			(effects
				(font
					(size 1.27 1.27)
					(thickness 0.15)
				)
				(justify left bottom)
				(hide yes)
			)
		)
		(property "License" "Apache-2.0"
			(at 250.19 177.8 0)
			(effects
				(font
					(size 1.27 1.27)
					(thickness 0.15)
				)
				(justify left bottom)
				(hide yes)
			)
		)
		(pin "1"
		)
		(instances
			(project "thunderbolt-gpu-adapter"
				(path ""
					(reference "#PWR045")
					(unit 1)
				)
			)
			(project "thunderbolt-to-10gbe-adapter"
				(path ""
					(reference "#PWR035")
					(unit 1)
				)
			)
		)
	)
	(symbol
		(lib_id "antmicroResistors0402:R_100k_0402")
		(at 147.32 191.77 90)
		(unit 1)
		(exclude_from_sim no)
		(in_bom yes)
		(on_board yes)
		(dnp no)
		(property "Reference" "R11"
			(at 148.59 187.96 90)
			(effects
				(font
					(size 1.27 1.27)
					(thickness 0.15)
				)
				(justify right)
			)
		)
		(property "Value" "R_100k_0402"
			(at 160.02 171.45 0)
			(effects
				(font
					(size 1.27 1.27)
					(thickness 0.15)
				)
				(justify left bottom)
				(hide yes)
			)
		)
		(property "Footprint" "antmicro-footprints:R_0402_1005Metric"
			(at 162.56 171.45 0)
			(effects
				(font
					(size 1.27 1.27)
					(thickness 0.15)
				)
				(justify left bottom)
				(hide yes)
			)
		)
		(property "Datasheet" "https://www.bourns.com/docs/product-datasheets/cr.pdf"
			(at 165.1 171.45 0)
			(effects
				(font
					(size 1.27 1.27)
					(thickness 0.15)
				)
				(justify left bottom)
				(hide yes)
			)
		)
		(property "Description" "SMD Chip Resistor, 100 kohm, ± 1%, 62.5 mW, 0402 [1005 Metric], Thick Film, General Purpose"
			(at 147.32 191.77 0)
			(effects
				(font
					(size 1.27 1.27)
				)
				(hide yes)
			)
		)
		(property "MPN" "CR0402-FX-1003GLF"
			(at 167.64 171.45 0)
			(effects
				(font
					(size 1.27 1.27)
					(thickness 0.15)
				)
				(justify left bottom)
				(hide yes)
			)
		)
		(property "Manufacturer" "Bourns"
			(at 170.18 171.45 0)
			(effects
				(font
					(size 1.27 1.27)
					(thickness 0.15)
				)
				(justify left bottom)
				(hide yes)
			)
		)
		(property "License" "Apache-2.0"
			(at 172.72 171.45 0)
			(effects
				(font
					(size 1.27 1.27)
					(thickness 0.15)
				)
				(justify left bottom)
				(hide yes)
			)
		)
		(property "Val" "100k"
			(at 148.59 190.5 90)
			(effects
				(font
					(size 1.27 1.27)
					(thickness 0.15)
				)
				(justify right)
			)
		)
		(property "Tolerance" "1%"
			(at 157.48 171.45 0)
			(effects
				(font
					(size 1.27 1.27)
				)
				(justify left bottom)
				(hide yes)
			)
		)
		(property "Author" "Antmicro"
			(at 175.26 171.45 0)
			(effects
				(font
					(size 1.27 1.27)
					(thickness 0.15)
				)
				(justify left bottom)
				(hide yes)
			)
		)
		(pin "1"
		)
		(pin "2"
		)
		(instances
			(project "thunderbolt-gpu-adapter"
				(path ""
					(reference "R4")
					(unit 1)
				)
			)
			(project "thunderbolt-to-10gbe-adapter"
				(path ""
					(reference "R11")
					(unit 1)
				)
			)
		)
	)
	(symbol
		(lib_id "antmicropower:PWR_FLAG")
		(at 289.56 59.69 270)
		(unit 1)
		(exclude_from_sim no)
		(in_bom yes)
		(on_board yes)
		(dnp no)
		(fields_autoplaced yes)
		(property "Reference" "#FLG08"
			(at 291.465 59.69 0)
			(effects
				(font
					(size 1.27 1.27)
				)
				(hide yes)
			)
		)
		(property "Value" "PWR_FLAG"
			(at 293.37 59.6899 90)
			(effects
				(font
					(size 1.27 1.27)
				)
				(justify left)
			)
		)
		(property "Footprint" ""
			(at 289.56 59.69 0)
			(effects
				(font
					(size 1.27 1.27)
				)
				(hide yes)
			)
		)
		(property "Datasheet" ""
			(at 289.56 59.69 0)
			(effects
				(font
					(size 1.27 1.27)
				)
				(hide yes)
			)
		)
		(property "Description" ""
			(at 289.56 59.69 0)
			(effects
				(font
					(size 1.27 1.27)
				)
				(hide yes)
			)
		)
		(pin "1"
		)
		(instances
			(project "thunderbolt-to-10gbe-adapter"
				(path ""
					(reference "#FLG08")
					(unit 1)
				)
			)
		)
	)
)
